FILE_TYPE = MACRO_DRAWING;
SET COLOR_WIRE YELLOW;
SET COLOR_PROP MONO;
SET COLOR_DOT WHITE;
SET COLOR_ARC YELLOW;
SET COLOR_BODY GREEN;
SET COLOR_NOTE MONO;
SET PROP_DISPLAY VALUE;
SET PAGE_NUMBER P100;
FORCEADD OFFPAGE..2
(-1475 3625);
FORCEPROP 2 LAST $XR0 77 
J 0
(-1286 3625);
DISPLAY 0.638298 (-1286 3625);
PAINT MONO (-1286 3625);
FORCEPROP 2 LAST $XR1 78 
J 0
(-1196 3625);
DISPLAY 0.638298 (-1196 3625);
PAINT MONO (-1196 3625);
FORCEPROP 2 LAST CDS_LIB mstr_standard
J 0
(-1475 3625);
PAINT MONO (-1475 3625);
DISPLAY INVISIBLE (-1475 3625);
FORCEPROP 1 LAST OFFPAGE TRUE
J 0
(-1150 3500);
PAINT GREEN (-1150 3500);
DISPLAY INVISIBLE (-1150 3500);
FORCEPROP 1 LAST COMMENT_BODY TRUE
J 0
(-1520 3530);
DISPLAY 1.170213 (-1520 3530);
PAINT GREEN (-1520 3530);
DISPLAY INVISIBLE (-1520 3530);
FORCEPROP 2 LAST PATH I1
J 0
(-1300 3700);
DISPLAY 1.021277 (-1300 3700);
PAINT ORANGE (-1300 3700);
DISPLAY INVISIBLE (-1300 3700);
FORCEADD PVDDQ_KLM..1
(-1900 2525);
FORCEPROP 3 LASTPIN (-1900 2475) SIG_NAME PVDDQ_KLM\g
J 0
(-1890 2485);
DISPLAY 0.659574 (-1890 2485);
PAINT MONO (-1890 2485);
DISPLAY INVISIBLE (-1890 2485);
FORCEPROP 1 LAST VOLTAGE 1.2V
J 0
(-1945 2482);
DISPLAY 0.340426 (-1945 2482);
PAINT SKYBLUE (-1945 2482);
DISPLAY INVISIBLE (-1945 2482);
FORCEPROP 2 LAST CDS_LIB mstr_symbols
J 0
(-1900 2525);
PAINT ORANGE (-1900 2525);
DISPLAY INVISIBLE (-1900 2525);
FORCEPROP 1 LAST BODY_TYPE PLUMBING
J 0
(-1945 2482);
DISPLAY 0.340426 (-1945 2482);
PAINT GREEN (-1945 2482);
DISPLAY INVISIBLE (-1945 2482);
FORCEPROP 1 LAST PATH I10
J 0
(-1850 2550);
DISPLAY 0.872340 (-1850 2550);
PAINT AQUA (-1850 2550);
DISPLAY INVISIBLE (-1850 2550);
FORCEPROP 1 LAST HDL_POWER PVDDQ_KLM
J 1
(-1900 2575);
DISPLAY 0.872340 (-1900 2575);
PAINT GREEN (-1900 2575);
DISPLAY INVISIBLE (-1900 2575);
FORCEADD RES..2
R 2
(-1900 2275);
FORCEPROP 1 LAST LOCATION R9M1
J 2
(-1945 2400);
DISPLAY 0.617021 (-1945 2400);
PAINT AQUA (-1945 2400);
FORCEPROP 1 LAST PART_NUMBER G21796-026
J 2
(-1940 2150);
DISPLAY 0.617021 (-1940 2150);
PAINT BLUE (-1940 2150);
FORCEPROP 1 LAST VALUE 1.00K
J 2
(-1945 2350);
DISPLAY 0.617021 (-1945 2350);
PAINT SKYBLUE (-1945 2350);
FORCEPROP 1 LAST TOLERANCE 1%
J 2
(-1945 2300);
DISPLAY 0.617021 (-1945 2300);
PAINT SKYBLUE (-1945 2300);
FORCEPROP 1 LAST PACK_TYPE 0402
J 2
(-1940 2100);
DISPLAY 0.617021 (-1940 2100);
PAINT SKYBLUE (-1940 2100);
FORCEPROP 1 LAST MATERIAL CHIP
J 2
(-1940 2200);
DISPLAY 0.617021 (-1940 2200);
PAINT SKYBLUE (-1940 2200);
FORCEPROP 1 LAST WATTAGE 1/16W
J 2
(-1940 2250);
DISPLAY 0.617021 (-1940 2250);
PAINT SKYBLUE (-1940 2250);
FORCEPROP 1 LASTPIN (-1900 2175) $PN 2
J 2
(-1905 2185);
DISPLAY 0.617021 (-1905 2185);
PAINT ORANGE (-1905 2185);
FORCEPROP 1 LASTPIN (-1900 2375) $PN 1
J 2
(-1905 2337);
DISPLAY 0.617021 (-1905 2337);
PAINT ORANGE (-1905 2337);
FORCEPROP 2 LAST BOM_COST SM_CONTROLLER
J 2
(-1900 2275);
PAINT MONO (-1900 2275);
DISPLAY INVISIBLE (-1900 2275);
FORCEPROP 2 LAST CDS_LIB mstr_discrete
J 0
(-1900 2275);
PAINT ORANGE (-1900 2275);
DISPLAY INVISIBLE (-1900 2275);
FORCEPROP 2 LAST SEC_TYPE 0402
J 0
(-1950 2500);
DISPLAY 1.021277 (-1950 2500);
PAINT ORANGE (-1950 2500);
DISPLAY INVISIBLE (-1950 2500);
FORCEPROP 2 LAST SEC 1
J 0
(-1950 2500);
DISPLAY 0.680851 (-1950 2500);
PAINT MONO (-1950 2500);
DISPLAY INVISIBLE (-1950 2500);
FORCEPROP 2 LAST CDS_LOCATION R9M1
J 2
(-1945 2400);
DISPLAY 0.617021 (-1945 2400);
PAINT AQUA (-1945 2400);
DISPLAY INVISIBLE (-1945 2400);
FORCEPROP 1 LAST PATH I11
J 2
(-1950 2450);
DISPLAY 0.978723 (-1950 2450);
PAINT WHITE (-1950 2450);
DISPLAY INVISIBLE (-1950 2450);
FORCEPROP 2 LAST ROOM MEM
J 2
(-1950 2450);
PAINT PEACH (-1950 2450);
DISPLAY INVISIBLE (-1950 2450);
FORCEADD OFFPAGE..1
(-2850 3625);
FORCEPROP 2 LAST $XR0 55 
J 0
(-3101 3625);
DISPLAY 0.638298 (-3101 3625);
PAINT MONO (-3101 3625);
FORCEPROP 2 LAST CDS_LIB mstr_standard
J 0
(-2850 3625);
PAINT MONO (-2850 3625);
DISPLAY INVISIBLE (-2850 3625);
FORCEPROP 1 LAST OFFPAGE TRUE
J 0
(-2525 3500);
PAINT GREEN (-2525 3500);
DISPLAY INVISIBLE (-2525 3500);
FORCEPROP 1 LAST COMMENT_BODY TRUE
J 0
(-2725 3525);
DISPLAY 1.170213 (-2725 3525);
PAINT GREEN (-2725 3525);
DISPLAY INVISIBLE (-2725 3525);
FORCEPROP 2 LAST PATH I12
J 0
(-2800 3700);
DISPLAY 1.021277 (-2800 3700);
PAINT ORANGE (-2800 3700);
DISPLAY INVISIBLE (-2800 3700);
FORCEADD RES..1
(-2125 1950);
FORCEPROP 1 LAST LOCATION R9M2
J 0
(-2150 2025);
DISPLAY 0.617021 (-2150 2025);
PAINT AQUA (-2150 2025);
FORCEPROP 1 LAST PART_NUMBER G21796-274
J 0
(-2250 1800);
DISPLAY 0.617021 (-2250 1800);
PAINT BLUE (-2250 1800);
FORCEPROP 1 LAST VALUE 2
J 2
(-2200 1900);
DISPLAY 0.617021 (-2200 1900);
PAINT SKYBLUE (-2200 1900);
FORCEPROP 1 LAST TOLERANCE 1.0%
J 0
(-2025 1850);
DISPLAY 0.617021 (-2025 1850);
PAINT SKYBLUE (-2025 1850);
FORCEPROP 1 LAST PACK_TYPE 0402
J 0
(-2250 1850);
DISPLAY 0.617021 (-2250 1850);
PAINT SKYBLUE (-2250 1850);
FORCEPROP 1 LAST MATERIAL CHIP
J 0
(-1900 1900);
DISPLAY 0.617021 (-1900 1900);
PAINT SKYBLUE (-1900 1900);
FORCEPROP 1 LAST WATTAGE 1/16W
J 2
(-1950 1900);
DISPLAY 0.617021 (-1950 1900);
PAINT SKYBLUE (-1950 1900);
FORCEPROP 1 LASTPIN (-2025 1950) $PN 2
J 0
(-2063 1962);
DISPLAY 0.617021 (-2063 1962);
PAINT MONO (-2063 1962);
FORCEPROP 1 LASTPIN (-2225 1950) $PN 1
J 0
(-2213 1962);
DISPLAY 0.617021 (-2213 1962);
PAINT MONO (-2213 1962);
FORCEPROP 2 LAST CDS_LIB mstr_discrete
J 0
(-2125 1950);
PAINT ORANGE (-2125 1950);
DISPLAY INVISIBLE (-2125 1950);
FORCEPROP 2 LAST SEC_TYPE 0402
J 0
(-2175 2150);
PAINT MONO (-2175 2150);
DISPLAY INVISIBLE (-2175 2150);
FORCEPROP 2 LAST BOM_COST PROC_SOCKET
J 0
(-2125 1950);
PAINT MONO (-2125 1950);
DISPLAY INVISIBLE (-2125 1950);
FORCEPROP 2 LAST SEC 1
J 0
(-2175 2150);
DISPLAY 0.936170 (-2175 2150);
PAINT MONO (-2175 2150);
DISPLAY INVISIBLE (-2175 2150);
FORCEPROP 2 LAST CDS_LOCATION R9M2
J 0
(-2150 2025);
DISPLAY 0.617021 (-2150 2025);
PAINT AQUA (-2150 2025);
DISPLAY INVISIBLE (-2150 2025);
FORCEPROP 1 LAST PATH I13
J 0
(-2175 2100);
DISPLAY 0.978723 (-2175 2100);
PAINT WHITE (-2175 2100);
DISPLAY INVISIBLE (-2175 2100);
FORCEPROP 0 LAST ROOM PROC
J 0
(-2200 1875);
DISPLAY 0.617021 (-2200 1875);
PAINT ORANGE (-2200 1875);
DISPLAY INVISIBLE (-2200 1875);
FORCEADD GND..1
(-2125 1300);
FORCEPROP 3 LASTPIN (-2125 1350) SIG_NAME GND\g
J 0
(-2115 1360);
DISPLAY 0.659574 (-2115 1360);
PAINT MONO (-2115 1360);
DISPLAY INVISIBLE (-2115 1360);
FORCEPROP 1 LAST VOLTAGE 0
J 0
(-2125 1300);
PAINT SKYBLUE (-2125 1300);
DISPLAY INVISIBLE (-2125 1300);
FORCEPROP 1 LAST SIZE 1B
J 0
(-2050 1250);
DISPLAY 1.170213 (-2050 1250);
PAINT GREEN (-2050 1250);
DISPLAY INVISIBLE (-2050 1250);
FORCEPROP 2 LAST CDS_LIB mstr_symbols
J 0
(-2125 1300);
PAINT MONO (-2125 1300);
DISPLAY INVISIBLE (-2125 1300);
FORCEPROP 1 LAST BODY_TYPE PLUMBING
J 0
(-2170 1257);
DISPLAY 0.340426 (-2170 1257);
PAINT GREEN (-2170 1257);
DISPLAY INVISIBLE (-2170 1257);
FORCEPROP 1 LAST PATH I14
J 0
(-2050 1300);
DISPLAY 0.872340 (-2050 1300);
PAINT AQUA (-2050 1300);
DISPLAY INVISIBLE (-2050 1300);
FORCEPROP 1 LAST HDL_POWER GND
J 0
(-2125 1450);
DISPLAY 1.170213 (-2125 1450);
PAINT GREEN (-2125 1450);
DISPLAY INVISIBLE (-2125 1450);
FORCEADD CAP_A..1
(-2350 1650);
FORCEPROP 1 LAST LOCATION C9M2
J 0
(-2300 1750);
DISPLAY 0.617021 (-2300 1750);
PAINT AQUA (-2300 1750);
FORCEPROP 1 LAST PART_NUMBER A36096-045
J 0
(-2300 1500);
DISPLAY 0.617021 (-2300 1500);
PAINT BLUE (-2300 1500);
FORCEPROP 1 LAST VALUE 0.01UF
J 0
(-2300 1700);
DISPLAY 0.617021 (-2300 1700);
PAINT SKYBLUE (-2300 1700);
FORCEPROP 1 LAST TOLERANCE 10%
J 0
(-2300 1600);
DISPLAY 0.617021 (-2300 1600);
PAINT SKYBLUE (-2300 1600);
FORCEPROP 1 LAST PACK_TYPE 0402V
J 0
(-2300 1450);
DISPLAY 0.617021 (-2300 1450);
PAINT SKYBLUE (-2300 1450);
FORCEPROP 1 LAST VOLTAGE 25V
J 0
(-2300 1650);
DISPLAY 0.617021 (-2300 1650);
PAINT SKYBLUE (-2300 1650);
FORCEPROP 1 LAST MATERIAL X7R
J 0
(-2300 1550);
DISPLAY 0.617021 (-2300 1550);
PAINT SKYBLUE (-2300 1550);
FORCEPROP 1 LASTPIN (-2350 1750) $PN 1
J 0
(-2340 1730);
DISPLAY 0.617021 (-2340 1730);
PAINT ORANGE (-2340 1730);
FORCEPROP 1 LASTPIN (-2350 1550) $PN 2
J 0
(-2340 1530);
DISPLAY 0.617021 (-2340 1530);
PAINT ORANGE (-2340 1530);
FORCEPROP 2 LAST CDS_LOCATION C9M2
J 0
(-2300 1750);
DISPLAY 0.617021 (-2300 1750);
PAINT AQUA (-2300 1750);
DISPLAY INVISIBLE (-2300 1750);
FORCEPROP 2 LAST BOM_COST SM_CONTROLLER
J 0
(-2350 1650);
PAINT MONO (-2350 1650);
DISPLAY INVISIBLE (-2350 1650);
FORCEPROP 2 LAST CDS_LIB dev_discrete
J 0
(-2350 1650);
PAINT ORANGE (-2350 1650);
DISPLAY INVISIBLE (-2350 1650);
FORCEPROP 2 LAST CDS_SEC 1
J 0
(-2300 1800);
PAINT ORANGE (-2300 1800);
DISPLAY INVISIBLE (-2300 1800);
FORCEPROP 2 LAST SEC_TYPE 0402V
J 0
(-2300 1850);
DISPLAY 1.021277 (-2300 1850);
PAINT ORANGE (-2300 1850);
DISPLAY INVISIBLE (-2300 1850);
FORCEPROP 2 LAST SEC 1
J 0
(-2300 1850);
DISPLAY 0.680851 (-2300 1850);
PAINT MONO (-2300 1850);
DISPLAY INVISIBLE (-2300 1850);
FORCEPROP 1 LAST PATH I15
J 0
(-2300 1800);
DISPLAY 0.978723 (-2300 1800);
PAINT WHITE (-2300 1800);
DISPLAY INVISIBLE (-2300 1800);
FORCEPROP 0 LAST ROOM MEM
J 0
(-2300 1400);
DISPLAY 0.978723 (-2300 1400);
PAINT ORANGE (-2300 1400);
DISPLAY INVISIBLE (-2300 1400);
FORCEADD OFFPAGE..1
(-2850 1950);
FORCEPROP 2 LAST $XR0 55 
J 0
(-3101 1950);
DISPLAY 0.638298 (-3101 1950);
PAINT MONO (-3101 1950);
FORCEPROP 2 LAST CDS_LIB mstr_standard
J 0
(-2850 1950);
PAINT MONO (-2850 1950);
DISPLAY INVISIBLE (-2850 1950);
FORCEPROP 1 LAST OFFPAGE TRUE
J 0
(-2525 1825);
PAINT GREEN (-2525 1825);
DISPLAY INVISIBLE (-2525 1825);
FORCEPROP 1 LAST COMMENT_BODY TRUE
J 0
(-2725 1850);
DISPLAY 1.170213 (-2725 1850);
PAINT GREEN (-2725 1850);
DISPLAY INVISIBLE (-2725 1850);
FORCEPROP 2 LAST PATH I16
J 0
(-2800 2025);
DISPLAY 1.021277 (-2800 2025);
PAINT ORANGE (-2800 2025);
DISPLAY INVISIBLE (-2800 2025);
FORCEADD PVDDQ_GHJ..1
(450 4200);
FORCEPROP 3 LASTPIN (450 4150) SIG_NAME PVDDQ_GHJ\g
J 0
(460 4160);
DISPLAY 0.659574 (460 4160);
PAINT MONO (460 4160);
DISPLAY INVISIBLE (460 4160);
FORCEPROP 1 LAST VOLTAGE 1.2V
J 0
(405 4157);
DISPLAY 0.340426 (405 4157);
PAINT SKYBLUE (405 4157);
DISPLAY INVISIBLE (405 4157);
FORCEPROP 2 LAST CDS_LIB mstr_symbols
J 0
(450 4200);
PAINT ORANGE (450 4200);
DISPLAY INVISIBLE (450 4200);
FORCEPROP 1 LAST BODY_TYPE PLUMBING
J 0
(405 4157);
DISPLAY 0.340426 (405 4157);
PAINT GREEN (405 4157);
DISPLAY INVISIBLE (405 4157);
FORCEPROP 1 LAST PATH I17
J 0
(500 4225);
DISPLAY 0.872340 (500 4225);
PAINT AQUA (500 4225);
DISPLAY INVISIBLE (500 4225);
FORCEPROP 1 LAST HDL_POWER PVDDQ_GHJ
J 1
(450 4250);
DISPLAY 0.872340 (450 4250);
PAINT GREEN (450 4250);
DISPLAY INVISIBLE (450 4250);
FORCEADD OFFPAGE..2
(875 3625);
FORCEPROP 2 LAST $XR0 79 
J 0
(1064 3625);
DISPLAY 0.638298 (1064 3625);
PAINT MONO (1064 3625);
FORCEPROP 2 LAST $XR1 80 
J 0
(1154 3625);
DISPLAY 0.638298 (1154 3625);
PAINT MONO (1154 3625);
FORCEPROP 2 LAST CDS_LIB mstr_standard
J 0
(875 3625);
PAINT MONO (875 3625);
DISPLAY INVISIBLE (875 3625);
FORCEPROP 1 LAST OFFPAGE TRUE
J 0
(1200 3500);
PAINT GREEN (1200 3500);
DISPLAY INVISIBLE (1200 3500);
FORCEPROP 1 LAST COMMENT_BODY TRUE
J 0
(830 3530);
DISPLAY 1.170213 (830 3530);
PAINT GREEN (830 3530);
DISPLAY INVISIBLE (830 3530);
FORCEPROP 2 LAST PATH I18
J 0
(1050 3700);
DISPLAY 1.021277 (1050 3700);
PAINT ORANGE (1050 3700);
DISPLAY INVISIBLE (1050 3700);
FORCEADD RES..2
R 2
(450 3950);
FORCEPROP 1 LAST LOCATION R1G2
J 2
(405 4075);
DISPLAY 0.617021 (405 4075);
PAINT AQUA (405 4075);
FORCEPROP 1 LAST PART_NUMBER G21796-026
J 2
(410 3825);
DISPLAY 0.617021 (410 3825);
PAINT BLUE (410 3825);
FORCEPROP 1 LAST VALUE 1.00K
J 2
(405 4025);
DISPLAY 0.617021 (405 4025);
PAINT SKYBLUE (405 4025);
FORCEPROP 1 LAST TOLERANCE 1%
J 2
(405 3975);
DISPLAY 0.617021 (405 3975);
PAINT SKYBLUE (405 3975);
FORCEPROP 1 LAST PACK_TYPE 0402
J 2
(410 3775);
DISPLAY 0.617021 (410 3775);
PAINT SKYBLUE (410 3775);
FORCEPROP 1 LAST MATERIAL CHIP
J 2
(410 3875);
DISPLAY 0.617021 (410 3875);
PAINT SKYBLUE (410 3875);
FORCEPROP 1 LAST WATTAGE 1/16W
J 2
(410 3925);
DISPLAY 0.617021 (410 3925);
PAINT SKYBLUE (410 3925);
FORCEPROP 1 LASTPIN (450 3850) $PN 2
J 2
(445 3860);
DISPLAY 0.617021 (445 3860);
PAINT ORANGE (445 3860);
FORCEPROP 1 LASTPIN (450 4050) $PN 1
J 2
(445 4012);
DISPLAY 0.617021 (445 4012);
PAINT ORANGE (445 4012);
FORCEPROP 2 LAST SEC_TYPE 0402
J 0
(400 4175);
DISPLAY 1.021277 (400 4175);
PAINT ORANGE (400 4175);
DISPLAY INVISIBLE (400 4175);
FORCEPROP 2 LAST BOM_COST SM_CONTROLLER
J 2
(450 3950);
PAINT MONO (450 3950);
DISPLAY INVISIBLE (450 3950);
FORCEPROP 2 LAST CDS_LIB mstr_discrete
J 0
(450 3950);
PAINT ORANGE (450 3950);
DISPLAY INVISIBLE (450 3950);
FORCEPROP 2 LAST SEC 1
J 0
(400 4175);
DISPLAY 0.680851 (400 4175);
PAINT MONO (400 4175);
DISPLAY INVISIBLE (400 4175);
FORCEPROP 2 LAST CDS_LOCATION R1G2
J 2
(405 4075);
DISPLAY 0.617021 (405 4075);
PAINT AQUA (405 4075);
DISPLAY INVISIBLE (405 4075);
FORCEPROP 1 LAST PATH I19
J 2
(400 4125);
DISPLAY 0.978723 (400 4125);
PAINT WHITE (400 4125);
DISPLAY INVISIBLE (400 4125);
FORCEPROP 2 LAST ROOM MEM
J 2
(400 4125);
PAINT PEACH (400 4125);
DISPLAY INVISIBLE (400 4125);
FORCEADD RES..2
R 2
(-1825 3300);
FORCEPROP 1 LAST LOCATION R1F6
J 2
(-1870 3425);
DISPLAY 0.617021 (-1870 3425);
PAINT AQUA (-1870 3425);
FORCEPROP 1 LAST PART_NUMBER G21796-026
J 2
(-1865 3175);
DISPLAY 0.617021 (-1865 3175);
PAINT BLUE (-1865 3175);
FORCEPROP 1 LAST VALUE 1.00K
J 2
(-1870 3375);
DISPLAY 0.617021 (-1870 3375);
PAINT SKYBLUE (-1870 3375);
FORCEPROP 1 LAST TOLERANCE 1%
J 2
(-1870 3325);
DISPLAY 0.617021 (-1870 3325);
PAINT SKYBLUE (-1870 3325);
FORCEPROP 1 LAST PACK_TYPE 0402
J 2
(-1865 3125);
DISPLAY 0.617021 (-1865 3125);
PAINT SKYBLUE (-1865 3125);
FORCEPROP 1 LAST MATERIAL CHIP
J 2
(-1865 3225);
DISPLAY 0.617021 (-1865 3225);
PAINT SKYBLUE (-1865 3225);
FORCEPROP 1 LAST WATTAGE 1/16W
J 2
(-1865 3275);
DISPLAY 0.617021 (-1865 3275);
PAINT SKYBLUE (-1865 3275);
FORCEPROP 1 LASTPIN (-1825 3200) $PN 2
J 2
(-1830 3210);
DISPLAY 0.617021 (-1830 3210);
PAINT ORANGE (-1830 3210);
FORCEPROP 1 LASTPIN (-1825 3400) $PN 1
J 2
(-1830 3362);
DISPLAY 0.617021 (-1830 3362);
PAINT ORANGE (-1830 3362);
FORCEPROP 2 LAST CDS_LIB mstr_discrete
J 0
(-1825 3300);
PAINT ORANGE (-1825 3300);
DISPLAY INVISIBLE (-1825 3300);
FORCEPROP 2 LAST BOM_COST SM_CONTROLLER
J 2
(-1825 3300);
PAINT MONO (-1825 3300);
DISPLAY INVISIBLE (-1825 3300);
FORCEPROP 2 LAST SEC_TYPE 0402
J 0
(-1875 3525);
DISPLAY 1.021277 (-1875 3525);
PAINT ORANGE (-1875 3525);
DISPLAY INVISIBLE (-1875 3525);
FORCEPROP 2 LAST SEC 1
J 0
(-1875 3525);
DISPLAY 0.680851 (-1875 3525);
PAINT MONO (-1875 3525);
DISPLAY INVISIBLE (-1875 3525);
FORCEPROP 2 LAST CDS_LOCATION R1F6
J 2
(-1870 3425);
DISPLAY 0.617021 (-1870 3425);
PAINT AQUA (-1870 3425);
DISPLAY INVISIBLE (-1870 3425);
FORCEPROP 1 LAST PATH I2
J 2
(-1875 3475);
DISPLAY 0.978723 (-1875 3475);
PAINT WHITE (-1875 3475);
DISPLAY INVISIBLE (-1875 3475);
FORCEPROP 2 LAST ROOM MEM
J 2
(-1875 3475);
PAINT PEACH (-1875 3475);
DISPLAY INVISIBLE (-1875 3475);
FORCEADD RES..2
R 2
(525 3300);
FORCEPROP 1 LAST LOCATION R1G3
J 2
(480 3425);
DISPLAY 0.617021 (480 3425);
PAINT AQUA (480 3425);
FORCEPROP 1 LAST PART_NUMBER G21796-026
J 2
(485 3175);
DISPLAY 0.617021 (485 3175);
PAINT BLUE (485 3175);
FORCEPROP 1 LAST VALUE 1.00K
J 2
(480 3375);
DISPLAY 0.617021 (480 3375);
PAINT SKYBLUE (480 3375);
FORCEPROP 1 LAST TOLERANCE 1%
J 2
(480 3325);
DISPLAY 0.617021 (480 3325);
PAINT SKYBLUE (480 3325);
FORCEPROP 1 LAST PACK_TYPE 0402
J 2
(485 3125);
DISPLAY 0.617021 (485 3125);
PAINT SKYBLUE (485 3125);
FORCEPROP 1 LAST MATERIAL CHIP
J 2
(485 3225);
DISPLAY 0.617021 (485 3225);
PAINT SKYBLUE (485 3225);
FORCEPROP 1 LAST WATTAGE 1/16W
J 2
(485 3275);
DISPLAY 0.617021 (485 3275);
PAINT SKYBLUE (485 3275);
FORCEPROP 1 LASTPIN (525 3200) $PN 2
J 2
(520 3210);
DISPLAY 0.617021 (520 3210);
PAINT ORANGE (520 3210);
FORCEPROP 1 LASTPIN (525 3400) $PN 1
J 2
(520 3362);
DISPLAY 0.617021 (520 3362);
PAINT ORANGE (520 3362);
FORCEPROP 2 LAST SEC_TYPE 0402
J 0
(475 3525);
DISPLAY 1.021277 (475 3525);
PAINT ORANGE (475 3525);
DISPLAY INVISIBLE (475 3525);
FORCEPROP 2 LAST BOM_COST SM_CONTROLLER
J 2
(525 3300);
PAINT MONO (525 3300);
DISPLAY INVISIBLE (525 3300);
FORCEPROP 2 LAST CDS_LIB mstr_discrete
J 0
(525 3300);
PAINT ORANGE (525 3300);
DISPLAY INVISIBLE (525 3300);
FORCEPROP 2 LAST SEC 1
J 0
(475 3525);
DISPLAY 0.680851 (475 3525);
PAINT MONO (475 3525);
DISPLAY INVISIBLE (475 3525);
FORCEPROP 2 LAST CDS_LOCATION R1G3
J 2
(480 3425);
DISPLAY 0.617021 (480 3425);
PAINT AQUA (480 3425);
DISPLAY INVISIBLE (480 3425);
FORCEPROP 1 LAST PATH I20
J 2
(475 3475);
DISPLAY 0.978723 (475 3475);
PAINT WHITE (475 3475);
DISPLAY INVISIBLE (475 3475);
FORCEPROP 2 LAST ROOM MEM
J 2
(475 3475);
PAINT PEACH (475 3475);
DISPLAY INVISIBLE (475 3475);
FORCEADD PVDDQ_KLM..1
(450 2525);
FORCEPROP 3 LASTPIN (450 2475) SIG_NAME PVDDQ_KLM\g
J 0
(460 2485);
DISPLAY 0.659574 (460 2485);
PAINT MONO (460 2485);
DISPLAY INVISIBLE (460 2485);
FORCEPROP 1 LAST VOLTAGE 1.2V
J 0
(405 2482);
DISPLAY 0.340426 (405 2482);
PAINT SKYBLUE (405 2482);
DISPLAY INVISIBLE (405 2482);
FORCEPROP 2 LAST CDS_LIB mstr_symbols
J 0
(450 2525);
PAINT ORANGE (450 2525);
DISPLAY INVISIBLE (450 2525);
FORCEPROP 1 LAST BODY_TYPE PLUMBING
J 0
(405 2482);
DISPLAY 0.340426 (405 2482);
PAINT GREEN (405 2482);
DISPLAY INVISIBLE (405 2482);
FORCEPROP 1 LAST PATH I21
J 0
(500 2550);
DISPLAY 0.872340 (500 2550);
PAINT AQUA (500 2550);
DISPLAY INVISIBLE (500 2550);
FORCEPROP 1 LAST HDL_POWER PVDDQ_KLM
J 1
(450 2575);
DISPLAY 0.872340 (450 2575);
PAINT GREEN (450 2575);
DISPLAY INVISIBLE (450 2575);
FORCEADD RES..2
R 2
(450 2275);
FORCEPROP 1 LAST LOCATION R9L7
J 2
(405 2400);
DISPLAY 0.617021 (405 2400);
PAINT AQUA (405 2400);
FORCEPROP 1 LAST PART_NUMBER G21796-026
J 2
(410 2150);
DISPLAY 0.617021 (410 2150);
PAINT BLUE (410 2150);
FORCEPROP 1 LAST VALUE 1.00K
J 2
(405 2350);
DISPLAY 0.617021 (405 2350);
PAINT SKYBLUE (405 2350);
FORCEPROP 1 LAST TOLERANCE 1%
J 2
(405 2300);
DISPLAY 0.617021 (405 2300);
PAINT SKYBLUE (405 2300);
FORCEPROP 1 LAST PACK_TYPE 0402
J 2
(410 2100);
DISPLAY 0.617021 (410 2100);
PAINT SKYBLUE (410 2100);
FORCEPROP 1 LAST MATERIAL CHIP
J 2
(410 2200);
DISPLAY 0.617021 (410 2200);
PAINT SKYBLUE (410 2200);
FORCEPROP 1 LAST WATTAGE 1/16W
J 2
(410 2250);
DISPLAY 0.617021 (410 2250);
PAINT SKYBLUE (410 2250);
FORCEPROP 1 LASTPIN (450 2175) $PN 2
J 2
(445 2185);
DISPLAY 0.617021 (445 2185);
PAINT ORANGE (445 2185);
FORCEPROP 1 LASTPIN (450 2375) $PN 1
J 2
(445 2337);
DISPLAY 0.617021 (445 2337);
PAINT ORANGE (445 2337);
FORCEPROP 2 LAST SEC_TYPE 0402
J 0
(400 2500);
DISPLAY 1.021277 (400 2500);
PAINT ORANGE (400 2500);
DISPLAY INVISIBLE (400 2500);
FORCEPROP 2 LAST CDS_LIB mstr_discrete
J 0
(450 2275);
PAINT ORANGE (450 2275);
DISPLAY INVISIBLE (450 2275);
FORCEPROP 2 LAST BOM_COST SM_CONTROLLER
J 2
(450 2275);
PAINT MONO (450 2275);
DISPLAY INVISIBLE (450 2275);
FORCEPROP 2 LAST SEC 1
J 0
(400 2500);
DISPLAY 0.680851 (400 2500);
PAINT MONO (400 2500);
DISPLAY INVISIBLE (400 2500);
FORCEPROP 2 LAST CDS_LOCATION R9L7
J 2
(405 2400);
DISPLAY 0.617021 (405 2400);
PAINT AQUA (405 2400);
DISPLAY INVISIBLE (405 2400);
FORCEPROP 1 LAST PATH I22
J 2
(400 2450);
DISPLAY 0.978723 (400 2450);
PAINT WHITE (400 2450);
DISPLAY INVISIBLE (400 2450);
FORCEPROP 2 LAST ROOM MEM
J 2
(400 2450);
PAINT PEACH (400 2450);
DISPLAY INVISIBLE (400 2450);
FORCEADD OFFPAGE..2
(875 1950);
FORCEPROP 2 LAST $XR0 85 
J 0
(1064 1950);
DISPLAY 0.638298 (1064 1950);
PAINT MONO (1064 1950);
FORCEPROP 2 LAST $XR1 86 
J 0
(1154 1950);
DISPLAY 0.638298 (1154 1950);
PAINT MONO (1154 1950);
FORCEPROP 2 LAST CDS_LIB mstr_standard
J 0
(875 1950);
PAINT MONO (875 1950);
DISPLAY INVISIBLE (875 1950);
FORCEPROP 1 LAST OFFPAGE TRUE
J 0
(1200 1825);
PAINT GREEN (1200 1825);
DISPLAY INVISIBLE (1200 1825);
FORCEPROP 1 LAST COMMENT_BODY TRUE
J 0
(830 1855);
DISPLAY 1.170213 (830 1855);
PAINT GREEN (830 1855);
DISPLAY INVISIBLE (830 1855);
FORCEPROP 2 LAST PATH I23
J 0
(1050 2025);
DISPLAY 1.021277 (1050 2025);
PAINT ORANGE (1050 2025);
DISPLAY INVISIBLE (1050 2025);
FORCEADD RES..2
R 2
(525 1625);
FORCEPROP 1 LAST LOCATION R9L6
J 2
(480 1750);
DISPLAY 0.617021 (480 1750);
PAINT AQUA (480 1750);
FORCEPROP 1 LAST PART_NUMBER G21796-026
J 2
(485 1500);
DISPLAY 0.617021 (485 1500);
PAINT BLUE (485 1500);
FORCEPROP 1 LAST VALUE 1.00K
J 2
(480 1700);
DISPLAY 0.617021 (480 1700);
PAINT SKYBLUE (480 1700);
FORCEPROP 1 LAST TOLERANCE 1%
J 2
(480 1650);
DISPLAY 0.617021 (480 1650);
PAINT SKYBLUE (480 1650);
FORCEPROP 1 LAST PACK_TYPE 0402
J 2
(485 1450);
DISPLAY 0.617021 (485 1450);
PAINT SKYBLUE (485 1450);
FORCEPROP 1 LAST MATERIAL CHIP
J 2
(485 1550);
DISPLAY 0.617021 (485 1550);
PAINT SKYBLUE (485 1550);
FORCEPROP 1 LAST WATTAGE 1/16W
J 2
(485 1600);
DISPLAY 0.617021 (485 1600);
PAINT SKYBLUE (485 1600);
FORCEPROP 1 LASTPIN (525 1525) $PN 2
J 2
(520 1535);
DISPLAY 0.617021 (520 1535);
PAINT ORANGE (520 1535);
FORCEPROP 1 LASTPIN (525 1725) $PN 1
J 2
(520 1687);
DISPLAY 0.617021 (520 1687);
PAINT ORANGE (520 1687);
FORCEPROP 2 LAST SEC_TYPE 0402
J 0
(475 1850);
DISPLAY 1.021277 (475 1850);
PAINT ORANGE (475 1850);
DISPLAY INVISIBLE (475 1850);
FORCEPROP 2 LAST BOM_COST PROC_SOCKET
J 2
(525 1625);
PAINT MONO (525 1625);
DISPLAY INVISIBLE (525 1625);
FORCEPROP 2 LAST CDS_LIB mstr_discrete
J 0
(525 1625);
PAINT ORANGE (525 1625);
DISPLAY INVISIBLE (525 1625);
FORCEPROP 2 LAST SEC 1
J 0
(475 1850);
DISPLAY 0.680851 (475 1850);
PAINT MONO (475 1850);
DISPLAY INVISIBLE (475 1850);
FORCEPROP 2 LAST CDS_LOCATION R9L6
J 2
(480 1750);
DISPLAY 0.617021 (480 1750);
PAINT AQUA (480 1750);
DISPLAY INVISIBLE (480 1750);
FORCEPROP 1 LAST PATH I24
J 2
(475 1800);
DISPLAY 0.978723 (475 1800);
PAINT WHITE (475 1800);
DISPLAY INVISIBLE (475 1800);
FORCEPROP 2 LAST ROOM PROC
J 2
(475 1800);
PAINT PEACH (475 1800);
DISPLAY INVISIBLE (475 1800);
FORCEADD RES..1
(225 3625);
FORCEPROP 1 LAST LOCATION R1G1
J 0
(175 3675);
DISPLAY 0.617021 (175 3675);
PAINT AQUA (175 3675);
FORCEPROP 1 LAST PART_NUMBER G21796-274
J 0
(100 3475);
DISPLAY 0.617021 (100 3475);
PAINT BLUE (100 3475);
FORCEPROP 1 LAST VALUE 2
J 2
(150 3575);
DISPLAY 0.617021 (150 3575);
PAINT SKYBLUE (150 3575);
FORCEPROP 1 LAST TOLERANCE 1.0%
J 0
(325 3525);
DISPLAY 0.617021 (325 3525);
PAINT SKYBLUE (325 3525);
FORCEPROP 1 LAST PACK_TYPE 0402
J 0
(100 3525);
DISPLAY 0.617021 (100 3525);
PAINT SKYBLUE (100 3525);
FORCEPROP 1 LAST MATERIAL CHIP
J 0
(450 3575);
DISPLAY 0.617021 (450 3575);
PAINT SKYBLUE (450 3575);
FORCEPROP 1 LAST WATTAGE 1/16W
J 2
(400 3575);
DISPLAY 0.617021 (400 3575);
PAINT SKYBLUE (400 3575);
FORCEPROP 1 LASTPIN (325 3625) $PN 2
J 0
(287 3637);
DISPLAY 0.617021 (287 3637);
PAINT ORANGE (287 3637);
FORCEPROP 1 LASTPIN (125 3625) $PN 1
J 0
(137 3637);
DISPLAY 0.617021 (137 3637);
PAINT ORANGE (137 3637);
FORCEPROP 2 LAST SEC_TYPE 0402
J 0
(175 3825);
DISPLAY 1.021277 (175 3825);
PAINT ORANGE (175 3825);
DISPLAY INVISIBLE (175 3825);
FORCEPROP 2 LAST CDS_LIB mstr_discrete
J 0
(225 3625);
PAINT ORANGE (225 3625);
DISPLAY INVISIBLE (225 3625);
FORCEPROP 2 LAST BOM_COST PROC_SOCKET
J 0
(225 3625);
PAINT MONO (225 3625);
DISPLAY INVISIBLE (225 3625);
FORCEPROP 2 LAST SEC 1
J 0
(175 3825);
DISPLAY 0.680851 (175 3825);
PAINT MONO (175 3825);
DISPLAY INVISIBLE (175 3825);
FORCEPROP 2 LAST CDS_LOCATION R1G1
J 0
(175 3675);
DISPLAY 0.617021 (175 3675);
PAINT AQUA (175 3675);
DISPLAY INVISIBLE (175 3675);
FORCEPROP 1 LAST PATH I25
J 0
(175 3775);
DISPLAY 0.978723 (175 3775);
PAINT WHITE (175 3775);
DISPLAY INVISIBLE (175 3775);
FORCEPROP 0 LAST ROOM PROC
J 0
(150 3550);
DISPLAY 0.617021 (150 3550);
PAINT ORANGE (150 3550);
DISPLAY INVISIBLE (150 3550);
FORCEADD CAP_A..1
(0 3325);
FORCEPROP 1 LAST LOCATION C1G8
J 0
(50 3425);
DISPLAY 0.617021 (50 3425);
PAINT AQUA (50 3425);
FORCEPROP 1 LAST PART_NUMBER A36096-045
J 0
(50 3175);
DISPLAY 0.617021 (50 3175);
PAINT BLUE (50 3175);
FORCEPROP 1 LAST VALUE 0.01UF
J 0
(50 3375);
DISPLAY 0.617021 (50 3375);
PAINT SKYBLUE (50 3375);
FORCEPROP 1 LAST TOLERANCE 10%
J 0
(50 3275);
DISPLAY 0.617021 (50 3275);
PAINT SKYBLUE (50 3275);
FORCEPROP 1 LAST PACK_TYPE 0402V
J 0
(50 3125);
DISPLAY 0.617021 (50 3125);
PAINT SKYBLUE (50 3125);
FORCEPROP 1 LAST VOLTAGE 25V
J 0
(50 3325);
DISPLAY 0.617021 (50 3325);
PAINT SKYBLUE (50 3325);
FORCEPROP 1 LAST MATERIAL X7R
J 0
(50 3225);
DISPLAY 0.617021 (50 3225);
PAINT SKYBLUE (50 3225);
FORCEPROP 1 LASTPIN (0 3425) $PN 1
J 0
(10 3405);
DISPLAY 0.617021 (10 3405);
PAINT ORANGE (10 3405);
FORCEPROP 1 LASTPIN (0 3225) $PN 2
J 0
(10 3205);
DISPLAY 0.617021 (10 3205);
PAINT ORANGE (10 3205);
FORCEPROP 2 LAST CDS_LOCATION C1G8
J 0
(50 3425);
DISPLAY 0.617021 (50 3425);
PAINT AQUA (50 3425);
DISPLAY INVISIBLE (50 3425);
FORCEPROP 2 LAST BOM_COST PROC_SOCKET
J 0
(0 3325);
PAINT MONO (0 3325);
DISPLAY INVISIBLE (0 3325);
FORCEPROP 2 LAST CDS_LIB dev_discrete
J 0
(0 3325);
PAINT ORANGE (0 3325);
DISPLAY INVISIBLE (0 3325);
FORCEPROP 2 LAST CDS_SEC 1
J 0
(50 3475);
PAINT ORANGE (50 3475);
DISPLAY INVISIBLE (50 3475);
FORCEPROP 2 LAST SEC_TYPE 0402V
J 0
(50 3525);
DISPLAY 1.021277 (50 3525);
PAINT ORANGE (50 3525);
DISPLAY INVISIBLE (50 3525);
FORCEPROP 2 LAST SEC 1
J 0
(50 3525);
DISPLAY 0.680851 (50 3525);
PAINT MONO (50 3525);
DISPLAY INVISIBLE (50 3525);
FORCEPROP 1 LAST PATH I26
J 0
(50 3475);
DISPLAY 0.978723 (50 3475);
PAINT WHITE (50 3475);
DISPLAY INVISIBLE (50 3475);
FORCEPROP 0 LAST ROOM PROC
J 0
(50 3075);
DISPLAY 0.978723 (50 3075);
PAINT ORANGE (50 3075);
DISPLAY INVISIBLE (50 3075);
FORCEADD OFFPAGE..1
(-500 3625);
FORCEPROP 2 LAST $XR0 55 
J 0
(-721 3625);
DISPLAY 0.638298 (-721 3625);
PAINT MONO (-721 3625);
FORCEPROP 2 LAST CDS_LIB mstr_standard
J 0
(-500 3625);
PAINT MONO (-500 3625);
DISPLAY INVISIBLE (-500 3625);
FORCEPROP 1 LAST OFFPAGE TRUE
J 0
(-175 3500);
PAINT GREEN (-175 3500);
DISPLAY INVISIBLE (-175 3500);
FORCEPROP 1 LAST COMMENT_BODY TRUE
J 0
(-375 3525);
DISPLAY 1.170213 (-375 3525);
PAINT GREEN (-375 3525);
DISPLAY INVISIBLE (-375 3525);
FORCEPROP 2 LAST PATH I27
J 0
(-450 3700);
DISPLAY 1.021277 (-450 3700);
PAINT ORANGE (-450 3700);
DISPLAY INVISIBLE (-450 3700);
FORCEADD GND..1
(225 2975);
FORCEPROP 3 LASTPIN (225 3025) SIG_NAME GND\g
J 0
(235 3035);
DISPLAY 0.659574 (235 3035);
PAINT MONO (235 3035);
DISPLAY INVISIBLE (235 3035);
FORCEPROP 1 LAST VOLTAGE 0
J 0
(225 2975);
PAINT SKYBLUE (225 2975);
DISPLAY INVISIBLE (225 2975);
FORCEPROP 2 LAST CDS_LIB mstr_symbols
J 0
(225 2975);
PAINT MONO (225 2975);
DISPLAY INVISIBLE (225 2975);
FORCEPROP 1 LAST SIZE 1B
J 0
(300 2925);
DISPLAY 1.170213 (300 2925);
PAINT GREEN (300 2925);
DISPLAY INVISIBLE (300 2925);
FORCEPROP 1 LAST BODY_TYPE PLUMBING
J 0
(180 2932);
DISPLAY 0.340426 (180 2932);
PAINT GREEN (180 2932);
DISPLAY INVISIBLE (180 2932);
FORCEPROP 1 LAST PATH I28
J 0
(300 2975);
DISPLAY 0.872340 (300 2975);
PAINT AQUA (300 2975);
DISPLAY INVISIBLE (300 2975);
FORCEPROP 1 LAST HDL_POWER GND
J 0
(225 3125);
DISPLAY 1.170213 (225 3125);
PAINT GREEN (225 3125);
DISPLAY INVISIBLE (225 3125);
FORCEADD RES..1
(225 1950);
FORCEPROP 1 LAST LOCATION R9L8
J 0
(200 2025);
DISPLAY 0.617021 (200 2025);
PAINT AQUA (200 2025);
FORCEPROP 1 LAST PART_NUMBER G21796-274
J 0
(100 1800);
DISPLAY 0.617021 (100 1800);
PAINT BLUE (100 1800);
FORCEPROP 1 LAST VALUE 2
J 2
(150 1900);
DISPLAY 0.617021 (150 1900);
PAINT SKYBLUE (150 1900);
FORCEPROP 1 LAST TOLERANCE 1.0%
J 0
(325 1850);
DISPLAY 0.617021 (325 1850);
PAINT SKYBLUE (325 1850);
FORCEPROP 1 LAST PACK_TYPE 0402
J 0
(100 1850);
DISPLAY 0.617021 (100 1850);
PAINT SKYBLUE (100 1850);
FORCEPROP 1 LAST MATERIAL CHIP
J 0
(450 1900);
DISPLAY 0.617021 (450 1900);
PAINT SKYBLUE (450 1900);
FORCEPROP 1 LAST WATTAGE 1/16W
J 2
(400 1900);
DISPLAY 0.617021 (400 1900);
PAINT SKYBLUE (400 1900);
FORCEPROP 1 LASTPIN (325 1950) $PN 2
J 0
(287 1962);
DISPLAY 0.617021 (287 1962);
PAINT MONO (287 1962);
FORCEPROP 1 LASTPIN (125 1950) $PN 1
J 0
(137 1962);
DISPLAY 0.617021 (137 1962);
PAINT MONO (137 1962);
FORCEPROP 2 LAST BOM_COST PROC_SOCKET
J 0
(225 1950);
PAINT MONO (225 1950);
DISPLAY INVISIBLE (225 1950);
FORCEPROP 2 LAST SEC_TYPE 0402
J 0
(175 2150);
PAINT MONO (175 2150);
DISPLAY INVISIBLE (175 2150);
FORCEPROP 2 LAST CDS_LIB mstr_discrete
J 0
(225 1950);
PAINT ORANGE (225 1950);
DISPLAY INVISIBLE (225 1950);
FORCEPROP 2 LAST SEC 1
J 0
(175 2150);
DISPLAY 0.936170 (175 2150);
PAINT MONO (175 2150);
DISPLAY INVISIBLE (175 2150);
FORCEPROP 2 LAST CDS_LOCATION R9L8
J 0
(200 2025);
DISPLAY 0.617021 (200 2025);
PAINT AQUA (200 2025);
DISPLAY INVISIBLE (200 2025);
FORCEPROP 1 LAST PATH I29
J 0
(175 2100);
DISPLAY 0.978723 (175 2100);
PAINT WHITE (175 2100);
DISPLAY INVISIBLE (175 2100);
FORCEPROP 0 LAST ROOM PROC
J 0
(150 1875);
DISPLAY 0.617021 (150 1875);
PAINT ORANGE (150 1875);
DISPLAY INVISIBLE (150 1875);
FORCEADD OFFPAGE..2
(-1475 1950);
FORCEPROP 2 LAST $XR0 83 
J 0
(-1286 1950);
DISPLAY 0.638298 (-1286 1950);
PAINT MONO (-1286 1950);
FORCEPROP 2 LAST $XR1 84 
J 0
(-1196 1950);
DISPLAY 0.638298 (-1196 1950);
PAINT MONO (-1196 1950);
FORCEPROP 2 LAST CDS_LIB mstr_standard
J 0
(-1475 1950);
PAINT MONO (-1475 1950);
DISPLAY INVISIBLE (-1475 1950);
FORCEPROP 1 LAST OFFPAGE TRUE
J 0
(-1150 1825);
PAINT GREEN (-1150 1825);
DISPLAY INVISIBLE (-1150 1825);
FORCEPROP 1 LAST COMMENT_BODY TRUE
J 0
(-1520 1855);
DISPLAY 1.170213 (-1520 1855);
PAINT GREEN (-1520 1855);
DISPLAY INVISIBLE (-1520 1855);
FORCEPROP 2 LAST PATH I3
J 0
(-1300 2025);
DISPLAY 1.021277 (-1300 2025);
PAINT ORANGE (-1300 2025);
DISPLAY INVISIBLE (-1300 2025);
FORCEADD CAP_A..1
(0 1650);
FORCEPROP 1 LAST LOCATION C9L8
J 0
(50 1750);
DISPLAY 0.617021 (50 1750);
PAINT AQUA (50 1750);
FORCEPROP 1 LAST PART_NUMBER A36096-045
J 0
(50 1500);
DISPLAY 0.617021 (50 1500);
PAINT BLUE (50 1500);
FORCEPROP 1 LAST VALUE 0.01UF
J 0
(50 1700);
DISPLAY 0.617021 (50 1700);
PAINT SKYBLUE (50 1700);
FORCEPROP 1 LAST TOLERANCE 10%
J 0
(50 1600);
DISPLAY 0.617021 (50 1600);
PAINT SKYBLUE (50 1600);
FORCEPROP 1 LAST PACK_TYPE 0402V
J 0
(50 1450);
DISPLAY 0.617021 (50 1450);
PAINT SKYBLUE (50 1450);
FORCEPROP 1 LAST VOLTAGE 25V
J 0
(50 1650);
DISPLAY 0.617021 (50 1650);
PAINT SKYBLUE (50 1650);
FORCEPROP 1 LAST MATERIAL X7R
J 0
(50 1550);
DISPLAY 0.617021 (50 1550);
PAINT SKYBLUE (50 1550);
FORCEPROP 1 LASTPIN (0 1750) $PN 1
J 0
(10 1730);
DISPLAY 0.617021 (10 1730);
PAINT ORANGE (10 1730);
FORCEPROP 1 LASTPIN (0 1550) $PN 2
J 0
(10 1530);
DISPLAY 0.617021 (10 1530);
PAINT ORANGE (10 1530);
FORCEPROP 2 LAST CDS_LOCATION C9L8
J 0
(50 1750);
DISPLAY 0.617021 (50 1750);
PAINT AQUA (50 1750);
DISPLAY INVISIBLE (50 1750);
FORCEPROP 2 LAST BOM_COST SM_CONTROLLER
J 0
(0 1650);
PAINT MONO (0 1650);
DISPLAY INVISIBLE (0 1650);
FORCEPROP 2 LAST CDS_LIB dev_discrete
J 0
(0 1650);
PAINT ORANGE (0 1650);
DISPLAY INVISIBLE (0 1650);
FORCEPROP 2 LAST CDS_SEC 1
J 0
(50 1800);
PAINT ORANGE (50 1800);
DISPLAY INVISIBLE (50 1800);
FORCEPROP 2 LAST SEC_TYPE 0402V
J 0
(50 1850);
DISPLAY 1.021277 (50 1850);
PAINT ORANGE (50 1850);
DISPLAY INVISIBLE (50 1850);
FORCEPROP 2 LAST SEC 1
J 0
(50 1850);
DISPLAY 0.680851 (50 1850);
PAINT MONO (50 1850);
DISPLAY INVISIBLE (50 1850);
FORCEPROP 1 LAST PATH I30
J 0
(50 1800);
DISPLAY 0.978723 (50 1800);
PAINT WHITE (50 1800);
DISPLAY INVISIBLE (50 1800);
FORCEPROP 0 LAST ROOM MEM
J 0
(50 1400);
DISPLAY 0.978723 (50 1400);
PAINT ORANGE (50 1400);
DISPLAY INVISIBLE (50 1400);
FORCEADD GND..1
(225 1300);
FORCEPROP 3 LASTPIN (225 1350) SIG_NAME GND\g
J 0
(235 1360);
DISPLAY 0.659574 (235 1360);
PAINT MONO (235 1360);
DISPLAY INVISIBLE (235 1360);
FORCEPROP 1 LAST VOLTAGE 0
J 0
(225 1300);
PAINT SKYBLUE (225 1300);
DISPLAY INVISIBLE (225 1300);
FORCEPROP 2 LAST CDS_LIB mstr_symbols
J 0
(225 1300);
PAINT MONO (225 1300);
DISPLAY INVISIBLE (225 1300);
FORCEPROP 1 LAST SIZE 1B
J 0
(300 1250);
DISPLAY 1.170213 (300 1250);
PAINT GREEN (300 1250);
DISPLAY INVISIBLE (300 1250);
FORCEPROP 1 LAST BODY_TYPE PLUMBING
J 0
(180 1257);
DISPLAY 0.340426 (180 1257);
PAINT GREEN (180 1257);
DISPLAY INVISIBLE (180 1257);
FORCEPROP 1 LAST PATH I31
J 0
(300 1300);
DISPLAY 0.872340 (300 1300);
PAINT AQUA (300 1300);
DISPLAY INVISIBLE (300 1300);
FORCEPROP 1 LAST HDL_POWER GND
J 0
(225 1450);
DISPLAY 1.170213 (225 1450);
PAINT GREEN (225 1450);
DISPLAY INVISIBLE (225 1450);
FORCEADD OFFPAGE..1
(-500 1950);
FORCEPROP 2 LAST $XR0 55 
J 0
(-721 1950);
DISPLAY 0.638298 (-721 1950);
PAINT MONO (-721 1950);
FORCEPROP 2 LAST CDS_LIB mstr_standard
J 0
(-500 1950);
PAINT MONO (-500 1950);
DISPLAY INVISIBLE (-500 1950);
FORCEPROP 1 LAST OFFPAGE TRUE
J 0
(-175 1825);
PAINT GREEN (-175 1825);
DISPLAY INVISIBLE (-175 1825);
FORCEPROP 1 LAST COMMENT_BODY TRUE
J 0
(-375 1850);
DISPLAY 1.170213 (-375 1850);
PAINT GREEN (-375 1850);
DISPLAY INVISIBLE (-375 1850);
FORCEPROP 2 LAST PATH I32
J 0
(-450 2025);
DISPLAY 1.021277 (-450 2025);
PAINT ORANGE (-450 2025);
DISPLAY INVISIBLE (-450 2025);
FORCEADD PVDDQ_GHJ..1
(2900 4200);
FORCEPROP 3 LASTPIN (2900 4150) SIG_NAME PVDDQ_GHJ\g
J 0
(2910 4160);
DISPLAY 0.659574 (2910 4160);
PAINT MONO (2910 4160);
DISPLAY INVISIBLE (2910 4160);
FORCEPROP 1 LAST VOLTAGE 1.2V
J 0
(2855 4157);
DISPLAY 0.340426 (2855 4157);
PAINT SKYBLUE (2855 4157);
DISPLAY INVISIBLE (2855 4157);
FORCEPROP 2 LAST CDS_LIB mstr_symbols
J 0
(2900 4200);
PAINT ORANGE (2900 4200);
DISPLAY INVISIBLE (2900 4200);
FORCEPROP 1 LAST BODY_TYPE PLUMBING
J 0
(2855 4157);
DISPLAY 0.340426 (2855 4157);
PAINT GREEN (2855 4157);
DISPLAY INVISIBLE (2855 4157);
FORCEPROP 1 LAST PATH I33
J 0
(2950 4225);
DISPLAY 0.872340 (2950 4225);
PAINT AQUA (2950 4225);
DISPLAY INVISIBLE (2950 4225);
FORCEPROP 1 LAST HDL_POWER PVDDQ_GHJ
J 1
(2900 4250);
DISPLAY 0.872340 (2900 4250);
PAINT GREEN (2900 4250);
DISPLAY INVISIBLE (2900 4250);
FORCEADD OFFPAGE..2
(3325 3625);
FORCEPROP 2 LAST $XR0 81 
J 0
(3514 3625);
DISPLAY 0.638298 (3514 3625);
PAINT MONO (3514 3625);
FORCEPROP 2 LAST $XR1 82 
J 0
(3604 3625);
DISPLAY 0.638298 (3604 3625);
PAINT MONO (3604 3625);
FORCEPROP 2 LAST CDS_LIB mstr_standard
J 0
(3325 3625);
PAINT MONO (3325 3625);
DISPLAY INVISIBLE (3325 3625);
FORCEPROP 1 LAST OFFPAGE TRUE
J 0
(3650 3500);
PAINT GREEN (3650 3500);
DISPLAY INVISIBLE (3650 3500);
FORCEPROP 1 LAST COMMENT_BODY TRUE
J 0
(3280 3530);
DISPLAY 1.170213 (3280 3530);
PAINT GREEN (3280 3530);
DISPLAY INVISIBLE (3280 3530);
FORCEPROP 2 LAST PATH I34
J 0
(3500 3700);
DISPLAY 1.021277 (3500 3700);
PAINT ORANGE (3500 3700);
DISPLAY INVISIBLE (3500 3700);
FORCEADD RES..2
R 2
(2900 3950);
FORCEPROP 1 LAST LOCATION R1G15
J 2
(2855 4075);
DISPLAY 0.617021 (2855 4075);
PAINT AQUA (2855 4075);
FORCEPROP 1 LAST PART_NUMBER G21796-026
J 2
(2860 3825);
DISPLAY 0.617021 (2860 3825);
PAINT BLUE (2860 3825);
FORCEPROP 1 LAST VALUE 1.00K
J 2
(2855 4025);
DISPLAY 0.617021 (2855 4025);
PAINT SKYBLUE (2855 4025);
FORCEPROP 1 LAST TOLERANCE 1%
J 2
(2855 3975);
DISPLAY 0.617021 (2855 3975);
PAINT SKYBLUE (2855 3975);
FORCEPROP 1 LAST PACK_TYPE 0402
J 2
(2860 3775);
DISPLAY 0.617021 (2860 3775);
PAINT SKYBLUE (2860 3775);
FORCEPROP 1 LAST MATERIAL CHIP
J 2
(2860 3875);
DISPLAY 0.617021 (2860 3875);
PAINT SKYBLUE (2860 3875);
FORCEPROP 1 LAST WATTAGE 1/16W
J 2
(2860 3925);
DISPLAY 0.617021 (2860 3925);
PAINT SKYBLUE (2860 3925);
FORCEPROP 1 LASTPIN (2900 3850) $PN 2
J 2
(2895 3860);
DISPLAY 0.617021 (2895 3860);
PAINT ORANGE (2895 3860);
FORCEPROP 1 LASTPIN (2900 4050) $PN 1
J 2
(2895 4012);
DISPLAY 0.617021 (2895 4012);
PAINT ORANGE (2895 4012);
FORCEPROP 2 LAST SEC_TYPE 0402
J 0
(2850 4175);
DISPLAY 1.021277 (2850 4175);
PAINT ORANGE (2850 4175);
DISPLAY INVISIBLE (2850 4175);
FORCEPROP 2 LAST BOM_COST SM_CONTROLLER
J 2
(2900 3950);
PAINT MONO (2900 3950);
DISPLAY INVISIBLE (2900 3950);
FORCEPROP 2 LAST CDS_LIB mstr_discrete
J 0
(2900 3950);
PAINT ORANGE (2900 3950);
DISPLAY INVISIBLE (2900 3950);
FORCEPROP 2 LAST SEC 1
J 0
(2850 4175);
DISPLAY 0.680851 (2850 4175);
PAINT MONO (2850 4175);
DISPLAY INVISIBLE (2850 4175);
FORCEPROP 2 LAST CDS_LOCATION R1G15
J 2
(2855 4075);
DISPLAY 0.617021 (2855 4075);
PAINT AQUA (2855 4075);
DISPLAY INVISIBLE (2855 4075);
FORCEPROP 1 LAST PATH I35
J 2
(2850 4125);
DISPLAY 0.978723 (2850 4125);
PAINT WHITE (2850 4125);
DISPLAY INVISIBLE (2850 4125);
FORCEPROP 2 LAST ROOM MEM
J 2
(2850 4125);
PAINT PEACH (2850 4125);
DISPLAY INVISIBLE (2850 4125);
FORCEADD RES..2
R 2
(2975 3300);
FORCEPROP 1 LAST LOCATION R1G17
J 2
(2930 3425);
DISPLAY 0.617021 (2930 3425);
PAINT AQUA (2930 3425);
FORCEPROP 1 LAST PART_NUMBER G21796-026
J 2
(2935 3175);
DISPLAY 0.617021 (2935 3175);
PAINT BLUE (2935 3175);
FORCEPROP 1 LAST VALUE 1.00K
J 2
(2930 3375);
DISPLAY 0.617021 (2930 3375);
PAINT SKYBLUE (2930 3375);
FORCEPROP 1 LAST TOLERANCE 1%
J 2
(2930 3325);
DISPLAY 0.617021 (2930 3325);
PAINT SKYBLUE (2930 3325);
FORCEPROP 1 LAST PACK_TYPE 0402
J 2
(2935 3125);
DISPLAY 0.617021 (2935 3125);
PAINT SKYBLUE (2935 3125);
FORCEPROP 1 LAST MATERIAL CHIP
J 2
(2935 3225);
DISPLAY 0.617021 (2935 3225);
PAINT SKYBLUE (2935 3225);
FORCEPROP 1 LAST WATTAGE 1/16W
J 2
(2935 3275);
DISPLAY 0.617021 (2935 3275);
PAINT SKYBLUE (2935 3275);
FORCEPROP 1 LASTPIN (2975 3200) $PN 2
J 2
(2970 3210);
DISPLAY 0.617021 (2970 3210);
PAINT ORANGE (2970 3210);
FORCEPROP 1 LASTPIN (2975 3400) $PN 1
J 2
(2970 3362);
DISPLAY 0.617021 (2970 3362);
PAINT ORANGE (2970 3362);
FORCEPROP 2 LAST SEC_TYPE 0402
J 0
(2925 3525);
DISPLAY 1.021277 (2925 3525);
PAINT ORANGE (2925 3525);
DISPLAY INVISIBLE (2925 3525);
FORCEPROP 2 LAST BOM_COST SM_CONTROLLER
J 2
(2975 3300);
PAINT MONO (2975 3300);
DISPLAY INVISIBLE (2975 3300);
FORCEPROP 2 LAST CDS_LIB mstr_discrete
J 0
(2975 3300);
PAINT ORANGE (2975 3300);
DISPLAY INVISIBLE (2975 3300);
FORCEPROP 2 LAST SEC 1
J 0
(2925 3525);
DISPLAY 0.680851 (2925 3525);
PAINT MONO (2925 3525);
DISPLAY INVISIBLE (2925 3525);
FORCEPROP 2 LAST CDS_LOCATION R1G17
J 2
(2930 3425);
DISPLAY 0.617021 (2930 3425);
PAINT AQUA (2930 3425);
DISPLAY INVISIBLE (2930 3425);
FORCEPROP 1 LAST PATH I36
J 2
(2925 3475);
DISPLAY 0.978723 (2925 3475);
PAINT WHITE (2925 3475);
DISPLAY INVISIBLE (2925 3475);
FORCEPROP 2 LAST ROOM MEM
J 2
(2925 3475);
PAINT PEACH (2925 3475);
DISPLAY INVISIBLE (2925 3475);
FORCEADD PVDDQ_KLM..1
(2900 2525);
FORCEPROP 3 LASTPIN (2900 2475) SIG_NAME PVDDQ_KLM\g
J 0
(2910 2485);
DISPLAY 0.659574 (2910 2485);
PAINT MONO (2910 2485);
DISPLAY INVISIBLE (2910 2485);
FORCEPROP 1 LAST VOLTAGE 1.2V
J 0
(2855 2482);
DISPLAY 0.340426 (2855 2482);
PAINT SKYBLUE (2855 2482);
DISPLAY INVISIBLE (2855 2482);
FORCEPROP 2 LAST CDS_LIB mstr_symbols
J 0
(2900 2525);
PAINT ORANGE (2900 2525);
DISPLAY INVISIBLE (2900 2525);
FORCEPROP 1 LAST BODY_TYPE PLUMBING
J 0
(2855 2482);
DISPLAY 0.340426 (2855 2482);
PAINT GREEN (2855 2482);
DISPLAY INVISIBLE (2855 2482);
FORCEPROP 1 LAST PATH I37
J 0
(2950 2550);
DISPLAY 0.872340 (2950 2550);
PAINT AQUA (2950 2550);
DISPLAY INVISIBLE (2950 2550);
FORCEPROP 1 LAST HDL_POWER PVDDQ_KLM
J 1
(2900 2575);
DISPLAY 0.872340 (2900 2575);
PAINT GREEN (2900 2575);
DISPLAY INVISIBLE (2900 2575);
FORCEADD RES..2
R 2
(2900 2275);
FORCEPROP 1 LAST LOCATION R9L2
J 2
(2855 2400);
DISPLAY 0.617021 (2855 2400);
PAINT AQUA (2855 2400);
FORCEPROP 1 LAST PART_NUMBER G21796-026
J 2
(2860 2150);
DISPLAY 0.617021 (2860 2150);
PAINT BLUE (2860 2150);
FORCEPROP 1 LAST VALUE 1.00K
J 2
(2855 2350);
DISPLAY 0.617021 (2855 2350);
PAINT SKYBLUE (2855 2350);
FORCEPROP 1 LAST TOLERANCE 1%
J 2
(2855 2300);
DISPLAY 0.617021 (2855 2300);
PAINT SKYBLUE (2855 2300);
FORCEPROP 1 LAST PACK_TYPE 0402
J 2
(2860 2100);
DISPLAY 0.617021 (2860 2100);
PAINT SKYBLUE (2860 2100);
FORCEPROP 1 LAST MATERIAL CHIP
J 2
(2860 2200);
DISPLAY 0.617021 (2860 2200);
PAINT SKYBLUE (2860 2200);
FORCEPROP 1 LAST WATTAGE 1/16W
J 2
(2860 2250);
DISPLAY 0.617021 (2860 2250);
PAINT SKYBLUE (2860 2250);
FORCEPROP 1 LASTPIN (2900 2175) $PN 2
J 2
(2895 2185);
DISPLAY 0.617021 (2895 2185);
PAINT ORANGE (2895 2185);
FORCEPROP 1 LASTPIN (2900 2375) $PN 1
J 2
(2895 2337);
DISPLAY 0.617021 (2895 2337);
PAINT ORANGE (2895 2337);
FORCEPROP 2 LAST SEC_TYPE 0402
J 0
(2850 2500);
DISPLAY 1.021277 (2850 2500);
PAINT ORANGE (2850 2500);
DISPLAY INVISIBLE (2850 2500);
FORCEPROP 2 LAST CDS_LIB mstr_discrete
J 0
(2900 2275);
PAINT ORANGE (2900 2275);
DISPLAY INVISIBLE (2900 2275);
FORCEPROP 2 LAST BOM_COST SM_CONTROLLER
J 2
(2900 2275);
PAINT MONO (2900 2275);
DISPLAY INVISIBLE (2900 2275);
FORCEPROP 2 LAST SEC 1
J 0
(2850 2500);
DISPLAY 0.680851 (2850 2500);
PAINT MONO (2850 2500);
DISPLAY INVISIBLE (2850 2500);
FORCEPROP 2 LAST CDS_LOCATION R9L2
J 2
(2855 2400);
DISPLAY 0.617021 (2855 2400);
PAINT AQUA (2855 2400);
DISPLAY INVISIBLE (2855 2400);
FORCEPROP 1 LAST PATH I38
J 2
(2850 2450);
DISPLAY 0.978723 (2850 2450);
PAINT WHITE (2850 2450);
DISPLAY INVISIBLE (2850 2450);
FORCEPROP 2 LAST ROOM MEM
J 2
(2850 2450);
PAINT PEACH (2850 2450);
DISPLAY INVISIBLE (2850 2450);
FORCEADD OFFPAGE..2
(3325 1950);
FORCEPROP 2 LAST $XR0 87 
J 0
(3514 1950);
DISPLAY 0.638298 (3514 1950);
PAINT MONO (3514 1950);
FORCEPROP 2 LAST $XR1 88 
J 0
(3604 1950);
DISPLAY 0.638298 (3604 1950);
PAINT MONO (3604 1950);
FORCEPROP 2 LAST CDS_LIB mstr_standard
J 0
(3325 1950);
PAINT MONO (3325 1950);
DISPLAY INVISIBLE (3325 1950);
FORCEPROP 1 LAST OFFPAGE TRUE
J 0
(3650 1825);
PAINT GREEN (3650 1825);
DISPLAY INVISIBLE (3650 1825);
FORCEPROP 1 LAST COMMENT_BODY TRUE
J 0
(3280 1855);
DISPLAY 1.170213 (3280 1855);
PAINT GREEN (3280 1855);
DISPLAY INVISIBLE (3280 1855);
FORCEPROP 2 LAST PATH I39
J 0
(3500 2025);
DISPLAY 1.021277 (3500 2025);
PAINT ORANGE (3500 2025);
DISPLAY INVISIBLE (3500 2025);
FORCEADD RES..2
R 2
(-1825 1625);
FORCEPROP 1 LAST LOCATION R9L11
J 2
(-1870 1750);
DISPLAY 0.617021 (-1870 1750);
PAINT AQUA (-1870 1750);
FORCEPROP 1 LAST PART_NUMBER G21796-026
J 2
(-1865 1500);
DISPLAY 0.617021 (-1865 1500);
PAINT BLUE (-1865 1500);
FORCEPROP 1 LAST VALUE 1.00K
J 2
(-1870 1700);
DISPLAY 0.617021 (-1870 1700);
PAINT SKYBLUE (-1870 1700);
FORCEPROP 1 LAST TOLERANCE 1%
J 2
(-1870 1650);
DISPLAY 0.617021 (-1870 1650);
PAINT SKYBLUE (-1870 1650);
FORCEPROP 1 LAST PACK_TYPE 0402
J 2
(-1865 1450);
DISPLAY 0.617021 (-1865 1450);
PAINT SKYBLUE (-1865 1450);
FORCEPROP 1 LAST MATERIAL CHIP
J 2
(-1865 1550);
DISPLAY 0.617021 (-1865 1550);
PAINT SKYBLUE (-1865 1550);
FORCEPROP 1 LAST WATTAGE 1/16W
J 2
(-1865 1600);
DISPLAY 0.617021 (-1865 1600);
PAINT SKYBLUE (-1865 1600);
FORCEPROP 1 LASTPIN (-1825 1525) $PN 2
J 2
(-1830 1535);
DISPLAY 0.617021 (-1830 1535);
PAINT ORANGE (-1830 1535);
FORCEPROP 1 LASTPIN (-1825 1725) $PN 1
J 2
(-1830 1687);
DISPLAY 0.617021 (-1830 1687);
PAINT ORANGE (-1830 1687);
FORCEPROP 2 LAST CDS_LIB mstr_discrete
J 0
(-1825 1625);
PAINT ORANGE (-1825 1625);
DISPLAY INVISIBLE (-1825 1625);
FORCEPROP 2 LAST BOM_COST PROC_SOCKET
J 2
(-1825 1625);
PAINT MONO (-1825 1625);
DISPLAY INVISIBLE (-1825 1625);
FORCEPROP 2 LAST SEC_TYPE 0402
J 0
(-1875 1850);
DISPLAY 1.021277 (-1875 1850);
PAINT ORANGE (-1875 1850);
DISPLAY INVISIBLE (-1875 1850);
FORCEPROP 2 LAST SEC 1
J 0
(-1875 1850);
DISPLAY 0.680851 (-1875 1850);
PAINT MONO (-1875 1850);
DISPLAY INVISIBLE (-1875 1850);
FORCEPROP 2 LAST CDS_LOCATION R9L11
J 2
(-1870 1750);
DISPLAY 0.617021 (-1870 1750);
PAINT AQUA (-1870 1750);
DISPLAY INVISIBLE (-1870 1750);
FORCEPROP 1 LAST PATH I4
J 2
(-1875 1800);
DISPLAY 0.978723 (-1875 1800);
PAINT WHITE (-1875 1800);
DISPLAY INVISIBLE (-1875 1800);
FORCEPROP 2 LAST ROOM PROC
J 2
(-1875 1800);
PAINT PEACH (-1875 1800);
DISPLAY INVISIBLE (-1875 1800);
FORCEADD RES..2
R 2
(2975 1625);
FORCEPROP 1 LAST LOCATION R9L1
J 2
(2930 1750);
DISPLAY 0.617021 (2930 1750);
PAINT AQUA (2930 1750);
FORCEPROP 1 LAST PART_NUMBER G21796-026
J 2
(2935 1500);
DISPLAY 0.617021 (2935 1500);
PAINT BLUE (2935 1500);
FORCEPROP 1 LAST VALUE 1.00K
J 2
(2930 1700);
DISPLAY 0.617021 (2930 1700);
PAINT SKYBLUE (2930 1700);
FORCEPROP 1 LAST TOLERANCE 1%
J 2
(2930 1650);
DISPLAY 0.617021 (2930 1650);
PAINT SKYBLUE (2930 1650);
FORCEPROP 1 LAST PACK_TYPE 0402
J 2
(2935 1450);
DISPLAY 0.617021 (2935 1450);
PAINT SKYBLUE (2935 1450);
FORCEPROP 1 LAST MATERIAL CHIP
J 2
(2935 1550);
DISPLAY 0.617021 (2935 1550);
PAINT SKYBLUE (2935 1550);
FORCEPROP 1 LAST WATTAGE 1/16W
J 2
(2935 1600);
DISPLAY 0.617021 (2935 1600);
PAINT SKYBLUE (2935 1600);
FORCEPROP 1 LASTPIN (2975 1525) $PN 2
J 2
(2970 1535);
DISPLAY 0.617021 (2970 1535);
PAINT ORANGE (2970 1535);
FORCEPROP 1 LASTPIN (2975 1725) $PN 1
J 2
(2970 1687);
DISPLAY 0.617021 (2970 1687);
PAINT ORANGE (2970 1687);
FORCEPROP 2 LAST SEC_TYPE 0402
J 0
(2925 1850);
DISPLAY 1.021277 (2925 1850);
PAINT ORANGE (2925 1850);
DISPLAY INVISIBLE (2925 1850);
FORCEPROP 2 LAST BOM_COST PROC_SOCKET
J 2
(2975 1625);
PAINT MONO (2975 1625);
DISPLAY INVISIBLE (2975 1625);
FORCEPROP 2 LAST CDS_LIB mstr_discrete
J 0
(2975 1625);
PAINT ORANGE (2975 1625);
DISPLAY INVISIBLE (2975 1625);
FORCEPROP 2 LAST SEC 1
J 0
(2925 1850);
DISPLAY 0.680851 (2925 1850);
PAINT MONO (2925 1850);
DISPLAY INVISIBLE (2925 1850);
FORCEPROP 2 LAST CDS_LOCATION R9L1
J 2
(2930 1750);
DISPLAY 0.617021 (2930 1750);
PAINT AQUA (2930 1750);
DISPLAY INVISIBLE (2930 1750);
FORCEPROP 1 LAST PATH I40
J 2
(2925 1800);
DISPLAY 0.978723 (2925 1800);
PAINT WHITE (2925 1800);
DISPLAY INVISIBLE (2925 1800);
FORCEPROP 2 LAST ROOM PROC
J 2
(2925 1800);
PAINT PEACH (2925 1800);
DISPLAY INVISIBLE (2925 1800);
FORCEADD RES..1
(2675 3625);
FORCEPROP 1 LAST LOCATION R1G14
J 0
(2625 3675);
DISPLAY 0.617021 (2625 3675);
PAINT AQUA (2625 3675);
FORCEPROP 1 LAST PART_NUMBER G21796-274
J 0
(2550 3475);
DISPLAY 0.617021 (2550 3475);
PAINT BLUE (2550 3475);
FORCEPROP 1 LAST VALUE 2
J 2
(2600 3575);
DISPLAY 0.617021 (2600 3575);
PAINT SKYBLUE (2600 3575);
FORCEPROP 1 LAST TOLERANCE 1.0%
J 0
(2775 3525);
DISPLAY 0.617021 (2775 3525);
PAINT SKYBLUE (2775 3525);
FORCEPROP 1 LAST PACK_TYPE 0402
J 0
(2550 3525);
DISPLAY 0.617021 (2550 3525);
PAINT SKYBLUE (2550 3525);
FORCEPROP 1 LAST MATERIAL CHIP
J 0
(2900 3575);
DISPLAY 0.617021 (2900 3575);
PAINT SKYBLUE (2900 3575);
FORCEPROP 1 LAST WATTAGE 1/16W
J 2
(2850 3575);
DISPLAY 0.617021 (2850 3575);
PAINT SKYBLUE (2850 3575);
FORCEPROP 1 LASTPIN (2775 3625) $PN 2
J 0
(2737 3637);
DISPLAY 0.617021 (2737 3637);
PAINT ORANGE (2737 3637);
FORCEPROP 1 LASTPIN (2575 3625) $PN 1
J 0
(2587 3637);
DISPLAY 0.617021 (2587 3637);
PAINT ORANGE (2587 3637);
FORCEPROP 2 LAST SEC_TYPE 0402
J 0
(2625 3825);
DISPLAY 1.021277 (2625 3825);
PAINT ORANGE (2625 3825);
DISPLAY INVISIBLE (2625 3825);
FORCEPROP 2 LAST CDS_LIB mstr_discrete
J 0
(2675 3625);
PAINT ORANGE (2675 3625);
DISPLAY INVISIBLE (2675 3625);
FORCEPROP 2 LAST BOM_COST PROC_SOCKET
J 0
(2675 3625);
PAINT MONO (2675 3625);
DISPLAY INVISIBLE (2675 3625);
FORCEPROP 2 LAST SEC 1
J 0
(2625 3825);
DISPLAY 0.680851 (2625 3825);
PAINT MONO (2625 3825);
DISPLAY INVISIBLE (2625 3825);
FORCEPROP 2 LAST CDS_LOCATION R1G14
J 0
(2625 3675);
DISPLAY 0.617021 (2625 3675);
PAINT AQUA (2625 3675);
DISPLAY INVISIBLE (2625 3675);
FORCEPROP 1 LAST PATH I41
J 0
(2625 3775);
DISPLAY 0.978723 (2625 3775);
PAINT WHITE (2625 3775);
DISPLAY INVISIBLE (2625 3775);
FORCEPROP 0 LAST ROOM PROC
J 0
(2600 3550);
DISPLAY 0.617021 (2600 3550);
PAINT ORANGE (2600 3550);
DISPLAY INVISIBLE (2600 3550);
FORCEADD CAP_A..1
(2450 3325);
FORCEPROP 1 LAST LOCATION C1G18
J 0
(2500 3425);
DISPLAY 0.617021 (2500 3425);
PAINT AQUA (2500 3425);
FORCEPROP 1 LAST PART_NUMBER A36096-045
J 0
(2500 3175);
DISPLAY 0.617021 (2500 3175);
PAINT BLUE (2500 3175);
FORCEPROP 1 LAST VALUE 0.01UF
J 0
(2500 3375);
DISPLAY 0.617021 (2500 3375);
PAINT SKYBLUE (2500 3375);
FORCEPROP 1 LAST TOLERANCE 10%
J 0
(2500 3275);
DISPLAY 0.617021 (2500 3275);
PAINT SKYBLUE (2500 3275);
FORCEPROP 1 LAST PACK_TYPE 0402V
J 0
(2500 3125);
DISPLAY 0.617021 (2500 3125);
PAINT SKYBLUE (2500 3125);
FORCEPROP 1 LAST VOLTAGE 25V
J 0
(2500 3325);
DISPLAY 0.617021 (2500 3325);
PAINT SKYBLUE (2500 3325);
FORCEPROP 1 LAST MATERIAL X7R
J 0
(2500 3225);
DISPLAY 0.617021 (2500 3225);
PAINT SKYBLUE (2500 3225);
FORCEPROP 1 LASTPIN (2450 3425) $PN 1
J 0
(2460 3405);
DISPLAY 0.617021 (2460 3405);
PAINT ORANGE (2460 3405);
FORCEPROP 1 LASTPIN (2450 3225) $PN 2
J 0
(2460 3205);
DISPLAY 0.617021 (2460 3205);
PAINT ORANGE (2460 3205);
FORCEPROP 2 LAST CDS_LOCATION C1G18
J 0
(2500 3425);
DISPLAY 0.617021 (2500 3425);
PAINT AQUA (2500 3425);
DISPLAY INVISIBLE (2500 3425);
FORCEPROP 2 LAST BOM_COST PROC_SOCKET
J 0
(2450 3325);
PAINT MONO (2450 3325);
DISPLAY INVISIBLE (2450 3325);
FORCEPROP 2 LAST CDS_LIB dev_discrete
J 0
(2450 3325);
PAINT ORANGE (2450 3325);
DISPLAY INVISIBLE (2450 3325);
FORCEPROP 2 LAST CDS_SEC 1
J 0
(2500 3475);
PAINT ORANGE (2500 3475);
DISPLAY INVISIBLE (2500 3475);
FORCEPROP 2 LAST SEC_TYPE 0402V
J 0
(2500 3525);
DISPLAY 1.021277 (2500 3525);
PAINT ORANGE (2500 3525);
DISPLAY INVISIBLE (2500 3525);
FORCEPROP 2 LAST SEC 1
J 0
(2500 3525);
DISPLAY 0.680851 (2500 3525);
PAINT MONO (2500 3525);
DISPLAY INVISIBLE (2500 3525);
FORCEPROP 1 LAST PATH I42
J 0
(2500 3475);
DISPLAY 0.978723 (2500 3475);
PAINT WHITE (2500 3475);
DISPLAY INVISIBLE (2500 3475);
FORCEPROP 0 LAST ROOM PROC
J 0
(2500 3075);
DISPLAY 0.978723 (2500 3075);
PAINT ORANGE (2500 3075);
DISPLAY INVISIBLE (2500 3075);
FORCEADD OFFPAGE..1
(1950 3625);
FORCEPROP 2 LAST $XR0 55 
J 0
(1699 3625);
DISPLAY 0.638298 (1699 3625);
PAINT MONO (1699 3625);
FORCEPROP 2 LAST CDS_LIB mstr_standard
J 0
(1950 3625);
PAINT MONO (1950 3625);
DISPLAY INVISIBLE (1950 3625);
FORCEPROP 1 LAST OFFPAGE TRUE
J 0
(2275 3500);
PAINT GREEN (2275 3500);
DISPLAY INVISIBLE (2275 3500);
FORCEPROP 1 LAST COMMENT_BODY TRUE
J 0
(2075 3525);
DISPLAY 1.170213 (2075 3525);
PAINT GREEN (2075 3525);
DISPLAY INVISIBLE (2075 3525);
FORCEPROP 2 LAST PATH I43
J 0
(2000 3700);
DISPLAY 1.021277 (2000 3700);
PAINT ORANGE (2000 3700);
DISPLAY INVISIBLE (2000 3700);
FORCEADD GND..1
(2675 2975);
FORCEPROP 3 LASTPIN (2675 3025) SIG_NAME GND\g
J 0
(2685 3035);
DISPLAY 0.659574 (2685 3035);
PAINT MONO (2685 3035);
DISPLAY INVISIBLE (2685 3035);
FORCEPROP 1 LAST VOLTAGE 0
J 0
(2675 2975);
PAINT SKYBLUE (2675 2975);
DISPLAY INVISIBLE (2675 2975);
FORCEPROP 2 LAST CDS_LIB mstr_symbols
J 0
(2675 2975);
PAINT MONO (2675 2975);
DISPLAY INVISIBLE (2675 2975);
FORCEPROP 1 LAST SIZE 1B
J 0
(2750 2925);
DISPLAY 1.170213 (2750 2925);
PAINT GREEN (2750 2925);
DISPLAY INVISIBLE (2750 2925);
FORCEPROP 1 LAST BODY_TYPE PLUMBING
J 0
(2630 2932);
DISPLAY 0.340426 (2630 2932);
PAINT GREEN (2630 2932);
DISPLAY INVISIBLE (2630 2932);
FORCEPROP 1 LAST PATH I44
J 0
(2750 2975);
DISPLAY 0.872340 (2750 2975);
PAINT AQUA (2750 2975);
DISPLAY INVISIBLE (2750 2975);
FORCEPROP 1 LAST HDL_POWER GND
J 0
(2675 3125);
DISPLAY 1.170213 (2675 3125);
PAINT GREEN (2675 3125);
DISPLAY INVISIBLE (2675 3125);
FORCEADD RES..1
(2675 1950);
FORCEPROP 1 LAST LOCATION R9L3
J 0
(2650 2025);
DISPLAY 0.617021 (2650 2025);
PAINT AQUA (2650 2025);
FORCEPROP 1 LAST PART_NUMBER G21796-274
J 0
(2550 1800);
DISPLAY 0.617021 (2550 1800);
PAINT BLUE (2550 1800);
FORCEPROP 1 LAST VALUE 2
J 2
(2600 1900);
DISPLAY 0.617021 (2600 1900);
PAINT SKYBLUE (2600 1900);
FORCEPROP 1 LAST TOLERANCE 1.0%
J 0
(2775 1850);
DISPLAY 0.617021 (2775 1850);
PAINT SKYBLUE (2775 1850);
FORCEPROP 1 LAST PACK_TYPE 0402
J 0
(2550 1850);
DISPLAY 0.617021 (2550 1850);
PAINT SKYBLUE (2550 1850);
FORCEPROP 1 LAST MATERIAL CHIP
J 0
(2900 1900);
DISPLAY 0.617021 (2900 1900);
PAINT SKYBLUE (2900 1900);
FORCEPROP 1 LAST WATTAGE 1/16W
J 2
(2850 1900);
DISPLAY 0.617021 (2850 1900);
PAINT SKYBLUE (2850 1900);
FORCEPROP 1 LASTPIN (2775 1950) $PN 2
J 0
(2737 1962);
DISPLAY 0.617021 (2737 1962);
PAINT MONO (2737 1962);
FORCEPROP 1 LASTPIN (2575 1950) $PN 1
J 0
(2587 1962);
DISPLAY 0.617021 (2587 1962);
PAINT MONO (2587 1962);
FORCEPROP 2 LAST BOM_COST PROC_SOCKET
J 0
(2675 1950);
PAINT MONO (2675 1950);
DISPLAY INVISIBLE (2675 1950);
FORCEPROP 2 LAST SEC_TYPE 0402
J 0
(2625 2150);
PAINT MONO (2625 2150);
DISPLAY INVISIBLE (2625 2150);
FORCEPROP 2 LAST CDS_LIB mstr_discrete
J 0
(2675 1950);
PAINT ORANGE (2675 1950);
DISPLAY INVISIBLE (2675 1950);
FORCEPROP 2 LAST SEC 1
J 0
(2625 2150);
DISPLAY 0.936170 (2625 2150);
PAINT MONO (2625 2150);
DISPLAY INVISIBLE (2625 2150);
FORCEPROP 2 LAST CDS_LOCATION R9L3
J 0
(2650 2025);
DISPLAY 0.617021 (2650 2025);
PAINT AQUA (2650 2025);
DISPLAY INVISIBLE (2650 2025);
FORCEPROP 1 LAST PATH I45
J 0
(2625 2100);
DISPLAY 0.978723 (2625 2100);
PAINT WHITE (2625 2100);
DISPLAY INVISIBLE (2625 2100);
FORCEPROP 0 LAST ROOM PROC
J 0
(2600 1875);
DISPLAY 0.617021 (2600 1875);
PAINT ORANGE (2600 1875);
DISPLAY INVISIBLE (2600 1875);
FORCEADD CAP_A..1
(2450 1650);
FORCEPROP 1 LAST LOCATION C9L3
J 0
(2500 1750);
DISPLAY 0.617021 (2500 1750);
PAINT AQUA (2500 1750);
FORCEPROP 1 LAST PART_NUMBER A36096-045
J 0
(2500 1500);
DISPLAY 0.617021 (2500 1500);
PAINT BLUE (2500 1500);
FORCEPROP 1 LAST VALUE 0.01UF
J 0
(2500 1700);
DISPLAY 0.617021 (2500 1700);
PAINT SKYBLUE (2500 1700);
FORCEPROP 1 LAST TOLERANCE 10%
J 0
(2500 1600);
DISPLAY 0.617021 (2500 1600);
PAINT SKYBLUE (2500 1600);
FORCEPROP 1 LAST PACK_TYPE 0402V
J 0
(2500 1450);
DISPLAY 0.617021 (2500 1450);
PAINT SKYBLUE (2500 1450);
FORCEPROP 1 LAST VOLTAGE 25V
J 0
(2500 1650);
DISPLAY 0.617021 (2500 1650);
PAINT SKYBLUE (2500 1650);
FORCEPROP 1 LAST MATERIAL X7R
J 0
(2500 1550);
DISPLAY 0.617021 (2500 1550);
PAINT SKYBLUE (2500 1550);
FORCEPROP 1 LASTPIN (2450 1750) $PN 1
J 0
(2460 1730);
DISPLAY 0.617021 (2460 1730);
PAINT ORANGE (2460 1730);
FORCEPROP 1 LASTPIN (2450 1550) $PN 2
J 0
(2460 1530);
DISPLAY 0.617021 (2460 1530);
PAINT ORANGE (2460 1530);
FORCEPROP 2 LAST CDS_LOCATION C9L3
J 0
(2500 1750);
DISPLAY 0.617021 (2500 1750);
PAINT AQUA (2500 1750);
DISPLAY INVISIBLE (2500 1750);
FORCEPROP 2 LAST BOM_COST SM_CONTROLLER
J 0
(2450 1650);
PAINT MONO (2450 1650);
DISPLAY INVISIBLE (2450 1650);
FORCEPROP 2 LAST CDS_LIB dev_discrete
J 0
(2450 1650);
PAINT ORANGE (2450 1650);
DISPLAY INVISIBLE (2450 1650);
FORCEPROP 2 LAST CDS_SEC 1
J 0
(2500 1800);
PAINT ORANGE (2500 1800);
DISPLAY INVISIBLE (2500 1800);
FORCEPROP 2 LAST SEC_TYPE 0402V
J 0
(2500 1850);
DISPLAY 1.021277 (2500 1850);
PAINT ORANGE (2500 1850);
DISPLAY INVISIBLE (2500 1850);
FORCEPROP 2 LAST SEC 1
J 0
(2500 1850);
DISPLAY 0.680851 (2500 1850);
PAINT MONO (2500 1850);
DISPLAY INVISIBLE (2500 1850);
FORCEPROP 1 LAST PATH I46
J 0
(2500 1800);
DISPLAY 0.978723 (2500 1800);
PAINT WHITE (2500 1800);
DISPLAY INVISIBLE (2500 1800);
FORCEPROP 0 LAST ROOM MEM
J 0
(2500 1400);
DISPLAY 0.978723 (2500 1400);
PAINT ORANGE (2500 1400);
DISPLAY INVISIBLE (2500 1400);
FORCEADD GND..1
(2675 1300);
FORCEPROP 3 LASTPIN (2675 1350) SIG_NAME GND\g
J 0
(2685 1360);
DISPLAY 0.659574 (2685 1360);
PAINT MONO (2685 1360);
DISPLAY INVISIBLE (2685 1360);
FORCEPROP 1 LAST VOLTAGE 0
J 0
(2675 1300);
PAINT SKYBLUE (2675 1300);
DISPLAY INVISIBLE (2675 1300);
FORCEPROP 2 LAST CDS_LIB mstr_symbols
J 0
(2675 1300);
PAINT MONO (2675 1300);
DISPLAY INVISIBLE (2675 1300);
FORCEPROP 1 LAST SIZE 1B
J 0
(2750 1250);
DISPLAY 1.170213 (2750 1250);
PAINT GREEN (2750 1250);
DISPLAY INVISIBLE (2750 1250);
FORCEPROP 1 LAST BODY_TYPE PLUMBING
J 0
(2630 1257);
DISPLAY 0.340426 (2630 1257);
PAINT GREEN (2630 1257);
DISPLAY INVISIBLE (2630 1257);
FORCEPROP 1 LAST PATH I47
J 0
(2750 1300);
DISPLAY 0.872340 (2750 1300);
PAINT AQUA (2750 1300);
DISPLAY INVISIBLE (2750 1300);
FORCEPROP 1 LAST HDL_POWER GND
J 0
(2675 1450);
DISPLAY 1.170213 (2675 1450);
PAINT GREEN (2675 1450);
DISPLAY INVISIBLE (2675 1450);
FORCEADD OFFPAGE..1
(1950 1950);
FORCEPROP 2 LAST $XR0 55 
J 0
(1699 1950);
DISPLAY 0.638298 (1699 1950);
PAINT MONO (1699 1950);
FORCEPROP 2 LAST CDS_LIB mstr_standard
J 0
(1950 1950);
PAINT MONO (1950 1950);
DISPLAY INVISIBLE (1950 1950);
FORCEPROP 1 LAST OFFPAGE TRUE
J 0
(2275 1825);
PAINT GREEN (2275 1825);
DISPLAY INVISIBLE (2275 1825);
FORCEPROP 1 LAST COMMENT_BODY TRUE
J 0
(2075 1850);
DISPLAY 1.170213 (2075 1850);
PAINT GREEN (2075 1850);
DISPLAY INVISIBLE (2075 1850);
FORCEPROP 2 LAST PATH I48
J 0
(2000 2025);
DISPLAY 1.021277 (2000 2025);
PAINT ORANGE (2000 2025);
DISPLAY INVISIBLE (2000 2025);
FORCEADD PVDDQ_GHJ..1
(-1900 4200);
FORCEPROP 3 LASTPIN (-1900 4150) SIG_NAME PVDDQ_GHJ\g
J 0
(-1890 4160);
DISPLAY 0.659574 (-1890 4160);
PAINT MONO (-1890 4160);
DISPLAY INVISIBLE (-1890 4160);
FORCEPROP 1 LAST VOLTAGE 1.2V
J 0
(-1945 4157);
DISPLAY 0.340426 (-1945 4157);
PAINT SKYBLUE (-1945 4157);
DISPLAY INVISIBLE (-1945 4157);
FORCEPROP 2 LAST CDS_LIB mstr_symbols
J 0
(-1900 4200);
PAINT ORANGE (-1900 4200);
DISPLAY INVISIBLE (-1900 4200);
FORCEPROP 1 LAST BODY_TYPE PLUMBING
J 0
(-1945 4157);
DISPLAY 0.340426 (-1945 4157);
PAINT GREEN (-1945 4157);
DISPLAY INVISIBLE (-1945 4157);
FORCEPROP 1 LAST PATH I5
J 0
(-1850 4225);
DISPLAY 0.872340 (-1850 4225);
PAINT AQUA (-1850 4225);
DISPLAY INVISIBLE (-1850 4225);
FORCEPROP 1 LAST HDL_POWER PVDDQ_GHJ
J 1
(-1900 4250);
DISPLAY 0.872340 (-1900 4250);
PAINT GREEN (-1900 4250);
DISPLAY INVISIBLE (-1900 4250);
FORCEADD RES..2
R 2
(-1900 3950);
FORCEPROP 1 LAST LOCATION R1F5
J 2
(-1945 4075);
DISPLAY 0.617021 (-1945 4075);
PAINT AQUA (-1945 4075);
FORCEPROP 1 LAST PART_NUMBER G21796-026
J 2
(-1940 3825);
DISPLAY 0.617021 (-1940 3825);
PAINT BLUE (-1940 3825);
FORCEPROP 1 LAST VALUE 1.00K
J 2
(-1945 4025);
DISPLAY 0.617021 (-1945 4025);
PAINT SKYBLUE (-1945 4025);
FORCEPROP 1 LAST TOLERANCE 1%
J 2
(-1945 3975);
DISPLAY 0.617021 (-1945 3975);
PAINT SKYBLUE (-1945 3975);
FORCEPROP 1 LAST PACK_TYPE 0402
J 2
(-1940 3775);
DISPLAY 0.617021 (-1940 3775);
PAINT SKYBLUE (-1940 3775);
FORCEPROP 1 LAST MATERIAL CHIP
J 2
(-1940 3875);
DISPLAY 0.617021 (-1940 3875);
PAINT SKYBLUE (-1940 3875);
FORCEPROP 1 LAST WATTAGE 1/16W
J 2
(-1940 3925);
DISPLAY 0.617021 (-1940 3925);
PAINT SKYBLUE (-1940 3925);
FORCEPROP 1 LASTPIN (-1900 3850) $PN 2
J 2
(-1905 3860);
DISPLAY 0.617021 (-1905 3860);
PAINT ORANGE (-1905 3860);
FORCEPROP 1 LASTPIN (-1900 4050) $PN 1
J 2
(-1905 4012);
DISPLAY 0.617021 (-1905 4012);
PAINT ORANGE (-1905 4012);
FORCEPROP 2 LAST CDS_LIB mstr_discrete
J 0
(-1900 3950);
PAINT ORANGE (-1900 3950);
DISPLAY INVISIBLE (-1900 3950);
FORCEPROP 2 LAST BOM_COST SM_CONTROLLER
J 2
(-1900 3950);
PAINT MONO (-1900 3950);
DISPLAY INVISIBLE (-1900 3950);
FORCEPROP 2 LAST SEC_TYPE 0402
J 0
(-1950 4175);
DISPLAY 1.021277 (-1950 4175);
PAINT ORANGE (-1950 4175);
DISPLAY INVISIBLE (-1950 4175);
FORCEPROP 2 LAST SEC 1
J 0
(-1950 4175);
DISPLAY 0.680851 (-1950 4175);
PAINT MONO (-1950 4175);
DISPLAY INVISIBLE (-1950 4175);
FORCEPROP 2 LAST CDS_LOCATION R1F5
J 2
(-1945 4075);
DISPLAY 0.617021 (-1945 4075);
PAINT AQUA (-1945 4075);
DISPLAY INVISIBLE (-1945 4075);
FORCEPROP 1 LAST PATH I6
J 2
(-1950 4125);
DISPLAY 0.978723 (-1950 4125);
PAINT WHITE (-1950 4125);
DISPLAY INVISIBLE (-1950 4125);
FORCEPROP 2 LAST ROOM MEM
J 2
(-1950 4125);
PAINT PEACH (-1950 4125);
DISPLAY INVISIBLE (-1950 4125);
FORCEADD RES..1
(-2125 3625);
FORCEPROP 1 LAST LOCATION R1F4
J 0
(-2175 3675);
DISPLAY 0.617021 (-2175 3675);
PAINT AQUA (-2175 3675);
FORCEPROP 1 LAST PART_NUMBER G21796-274
J 0
(-2250 3475);
DISPLAY 0.617021 (-2250 3475);
PAINT BLUE (-2250 3475);
FORCEPROP 1 LAST VALUE 2
J 2
(-2200 3575);
DISPLAY 0.617021 (-2200 3575);
PAINT SKYBLUE (-2200 3575);
FORCEPROP 1 LAST TOLERANCE 1.0%
J 0
(-2025 3525);
DISPLAY 0.617021 (-2025 3525);
PAINT SKYBLUE (-2025 3525);
FORCEPROP 1 LAST PACK_TYPE 0402
J 0
(-2250 3525);
DISPLAY 0.617021 (-2250 3525);
PAINT SKYBLUE (-2250 3525);
FORCEPROP 1 LAST MATERIAL CHIP
J 0
(-1900 3575);
DISPLAY 0.617021 (-1900 3575);
PAINT SKYBLUE (-1900 3575);
FORCEPROP 1 LAST WATTAGE 1/16W
J 2
(-1950 3575);
DISPLAY 0.617021 (-1950 3575);
PAINT SKYBLUE (-1950 3575);
FORCEPROP 1 LASTPIN (-2025 3625) $PN 2
J 0
(-2063 3637);
DISPLAY 0.617021 (-2063 3637);
PAINT ORANGE (-2063 3637);
FORCEPROP 1 LASTPIN (-2225 3625) $PN 1
J 0
(-2213 3637);
DISPLAY 0.617021 (-2213 3637);
PAINT ORANGE (-2213 3637);
FORCEPROP 2 LAST BOM_COST PROC_SOCKET
J 0
(-2125 3625);
PAINT MONO (-2125 3625);
DISPLAY INVISIBLE (-2125 3625);
FORCEPROP 2 LAST CDS_LIB mstr_discrete
J 0
(-2125 3625);
PAINT ORANGE (-2125 3625);
DISPLAY INVISIBLE (-2125 3625);
FORCEPROP 2 LAST SEC_TYPE 0402
J 0
(-2175 3825);
DISPLAY 1.021277 (-2175 3825);
PAINT ORANGE (-2175 3825);
DISPLAY INVISIBLE (-2175 3825);
FORCEPROP 2 LAST SEC 1
J 0
(-2175 3825);
DISPLAY 0.680851 (-2175 3825);
PAINT MONO (-2175 3825);
DISPLAY INVISIBLE (-2175 3825);
FORCEPROP 2 LAST CDS_LOCATION R1F4
J 0
(-2175 3675);
DISPLAY 0.617021 (-2175 3675);
PAINT AQUA (-2175 3675);
DISPLAY INVISIBLE (-2175 3675);
FORCEPROP 1 LAST PATH I7
J 0
(-2175 3775);
DISPLAY 0.978723 (-2175 3775);
PAINT WHITE (-2175 3775);
DISPLAY INVISIBLE (-2175 3775);
FORCEPROP 0 LAST ROOM PROC
J 0
(-2200 3550);
DISPLAY 0.617021 (-2200 3550);
PAINT ORANGE (-2200 3550);
DISPLAY INVISIBLE (-2200 3550);
FORCEADD CAP_A..1
(-2350 3325);
FORCEPROP 1 LAST LOCATION C1F19
J 0
(-2300 3425);
DISPLAY 0.617021 (-2300 3425);
PAINT AQUA (-2300 3425);
FORCEPROP 1 LAST PART_NUMBER A36096-045
J 0
(-2300 3175);
DISPLAY 0.617021 (-2300 3175);
PAINT BLUE (-2300 3175);
FORCEPROP 1 LAST VALUE 0.01UF
J 0
(-2300 3375);
DISPLAY 0.617021 (-2300 3375);
PAINT SKYBLUE (-2300 3375);
FORCEPROP 1 LAST TOLERANCE 10%
J 0
(-2300 3275);
DISPLAY 0.617021 (-2300 3275);
PAINT SKYBLUE (-2300 3275);
FORCEPROP 1 LAST PACK_TYPE 0402V
J 0
(-2300 3125);
DISPLAY 0.617021 (-2300 3125);
PAINT SKYBLUE (-2300 3125);
FORCEPROP 1 LAST VOLTAGE 25V
J 0
(-2300 3325);
DISPLAY 0.617021 (-2300 3325);
PAINT SKYBLUE (-2300 3325);
FORCEPROP 1 LAST MATERIAL X7R
J 0
(-2300 3225);
DISPLAY 0.617021 (-2300 3225);
PAINT SKYBLUE (-2300 3225);
FORCEPROP 1 LASTPIN (-2350 3425) $PN 1
J 0
(-2340 3405);
DISPLAY 0.617021 (-2340 3405);
PAINT ORANGE (-2340 3405);
FORCEPROP 1 LASTPIN (-2350 3225) $PN 2
J 0
(-2340 3205);
DISPLAY 0.617021 (-2340 3205);
PAINT ORANGE (-2340 3205);
FORCEPROP 2 LAST CDS_LOCATION C1F19
J 0
(-2300 3425);
DISPLAY 0.617021 (-2300 3425);
PAINT AQUA (-2300 3425);
DISPLAY INVISIBLE (-2300 3425);
FORCEPROP 2 LAST BOM_COST PROC_SOCKET
J 0
(-2350 3325);
PAINT MONO (-2350 3325);
DISPLAY INVISIBLE (-2350 3325);
FORCEPROP 2 LAST CDS_LIB dev_discrete
J 0
(-2350 3325);
PAINT ORANGE (-2350 3325);
DISPLAY INVISIBLE (-2350 3325);
FORCEPROP 2 LAST CDS_SEC 1
J 0
(-2300 3475);
PAINT ORANGE (-2300 3475);
DISPLAY INVISIBLE (-2300 3475);
FORCEPROP 2 LAST SEC_TYPE 0402V
J 0
(-2300 3525);
DISPLAY 1.021277 (-2300 3525);
PAINT ORANGE (-2300 3525);
DISPLAY INVISIBLE (-2300 3525);
FORCEPROP 2 LAST SEC 1
J 0
(-2300 3525);
DISPLAY 0.680851 (-2300 3525);
PAINT MONO (-2300 3525);
DISPLAY INVISIBLE (-2300 3525);
FORCEPROP 1 LAST PATH I8
J 0
(-2300 3475);
DISPLAY 0.978723 (-2300 3475);
PAINT WHITE (-2300 3475);
DISPLAY INVISIBLE (-2300 3475);
FORCEPROP 0 LAST ROOM PROC
J 0
(-2300 3075);
DISPLAY 0.978723 (-2300 3075);
PAINT ORANGE (-2300 3075);
DISPLAY INVISIBLE (-2300 3075);
FORCEADD GND..1
(-2125 2975);
FORCEPROP 3 LASTPIN (-2125 3025) SIG_NAME GND\g
J 0
(-2115 3035);
DISPLAY 0.659574 (-2115 3035);
PAINT MONO (-2115 3035);
DISPLAY INVISIBLE (-2115 3035);
FORCEPROP 1 LAST VOLTAGE 0
J 0
(-2125 2975);
PAINT SKYBLUE (-2125 2975);
DISPLAY INVISIBLE (-2125 2975);
FORCEPROP 1 LAST SIZE 1B
J 0
(-2050 2925);
DISPLAY 1.170213 (-2050 2925);
PAINT GREEN (-2050 2925);
DISPLAY INVISIBLE (-2050 2925);
FORCEPROP 2 LAST CDS_LIB mstr_symbols
J 0
(-2125 2975);
PAINT MONO (-2125 2975);
DISPLAY INVISIBLE (-2125 2975);
FORCEPROP 1 LAST BODY_TYPE PLUMBING
J 0
(-2170 2932);
DISPLAY 0.340426 (-2170 2932);
PAINT GREEN (-2170 2932);
DISPLAY INVISIBLE (-2170 2932);
FORCEPROP 1 LAST PATH I9
J 0
(-2050 2975);
DISPLAY 0.872340 (-2050 2975);
PAINT AQUA (-2050 2975);
DISPLAY INVISIBLE (-2050 2975);
FORCEPROP 1 LAST HDL_POWER GND
J 0
(-2125 3125);
DISPLAY 1.170213 (-2125 3125);
PAINT GREEN (-2125 3125);
DISPLAY INVISIBLE (-2125 3125);
FORCEADD CAD_NOTE..1
(-825 2800);
FORCEPROP 0 LAST L1 PLACE BETWEEN DIMM_L1 & L2
J 0
(-975 2675);
PAINT WHITE (-975 2675);
FORCEPROP 2 LAST CDS_LIB mstr_symbols
J 0
(-825 2800);
PAINT WHITE (-825 2800);
DISPLAY INVISIBLE (-825 2800);
FORCEPROP 2 LAST BOM_COST SM_CONTROLLER
J 0
(-975 2750);
PAINT WHITE (-975 2750);
DISPLAY INVISIBLE (-975 2750);
FORCEPROP 1 LAST COMMENT_BODY TRUE
J 0
(-800 2900);
DISPLAY 1.319149 (-800 2900);
PAINT WHITE (-800 2900);
DISPLAY INVISIBLE (-800 2900);
FORCEPROP 2 LAST ROOM BMC
J 0
(-975 2750);
PAINT WHITE (-975 2750);
DISPLAY INVISIBLE (-975 2750);
FORCEADD CAD_NOTE..1
(1625 2800);
FORCEPROP 0 LAST L1 PLACE BETWEEN DIMM_M1 & M2
J 0
(1500 2700);
PAINT WHITE (1500 2700);
FORCEPROP 2 LAST CDS_LIB mstr_symbols
J 0
(1625 2800);
PAINT WHITE (1625 2800);
DISPLAY INVISIBLE (1625 2800);
FORCEPROP 2 LAST BOM_COST SM_CONTROLLER
J 0
(1475 2750);
PAINT WHITE (1475 2750);
DISPLAY INVISIBLE (1475 2750);
FORCEPROP 1 LAST COMMENT_BODY TRUE
J 0
(1650 2900);
DISPLAY 1.319149 (1650 2900);
PAINT WHITE (1650 2900);
DISPLAY INVISIBLE (1650 2900);
FORCEPROP 2 LAST ROOM BMC
J 0
(1475 2750);
PAINT WHITE (1475 2750);
DISPLAY INVISIBLE (1475 2750);
FORCEADD CAD_NOTE..1
(-3175 2800);
FORCEPROP 0 LAST L1 PLACE BETWEEN DIMM_K1 & K2
J 0
(-3350 2650);
PAINT WHITE (-3350 2650);
FORCEPROP 2 LAST BOM_COST SM_CONTROLLER
J 0
(-3325 2750);
PAINT WHITE (-3325 2750);
DISPLAY INVISIBLE (-3325 2750);
FORCEPROP 2 LAST CDS_LIB mstr_symbols
J 0
(-3175 2800);
PAINT WHITE (-3175 2800);
DISPLAY INVISIBLE (-3175 2800);
FORCEPROP 1 LAST COMMENT_BODY TRUE
J 0
(-3150 2900);
DISPLAY 1.319149 (-3150 2900);
PAINT WHITE (-3150 2900);
DISPLAY INVISIBLE (-3150 2900);
FORCEPROP 2 LAST ROOM BMC
J 0
(-3325 2750);
PAINT WHITE (-3325 2750);
DISPLAY INVISIBLE (-3325 2750);
FORCEADD CAD_NOTE..1
(-825 4475);
FORCEPROP 0 LAST L1 PLACE BETWEEN DIMM_H1 & H2
J 0
(-975 4350);
PAINT WHITE (-975 4350);
FORCEPROP 2 LAST CDS_LIB mstr_symbols
J 0
(-825 4475);
PAINT WHITE (-825 4475);
DISPLAY INVISIBLE (-825 4475);
FORCEPROP 2 LAST BOM_COST SM_CONTROLLER
J 0
(-975 4425);
PAINT WHITE (-975 4425);
DISPLAY INVISIBLE (-975 4425);
FORCEPROP 1 LAST COMMENT_BODY TRUE
J 0
(-800 4575);
DISPLAY 1.319149 (-800 4575);
PAINT WHITE (-800 4575);
DISPLAY INVISIBLE (-800 4575);
FORCEPROP 2 LAST ROOM BMC
J 0
(-975 4425);
PAINT WHITE (-975 4425);
DISPLAY INVISIBLE (-975 4425);
FORCEADD CAD_NOTE..1
(1625 4475);
FORCEPROP 0 LAST L1 PLACE BETWEEN DIMM_ J1 & J2
J 0
(1475 4375);
PAINT WHITE (1475 4375);
FORCEPROP 2 LAST CDS_LIB mstr_symbols
J 0
(1625 4475);
PAINT WHITE (1625 4475);
DISPLAY INVISIBLE (1625 4475);
FORCEPROP 2 LAST BOM_COST SM_CONTROLLER
J 0
(1475 4425);
PAINT WHITE (1475 4425);
DISPLAY INVISIBLE (1475 4425);
FORCEPROP 1 LAST COMMENT_BODY TRUE
J 0
(1650 4575);
DISPLAY 1.319149 (1650 4575);
PAINT WHITE (1650 4575);
DISPLAY INVISIBLE (1650 4575);
FORCEPROP 2 LAST ROOM BMC
J 0
(1475 4425);
PAINT WHITE (1475 4425);
DISPLAY INVISIBLE (1475 4425);
FORCEADD CAD_NOTE..1
(-3175 4475);
FORCEPROP 0 LAST L1 PLACE BETWEEN DIMM_G1 & G2
J 0
(-3325 4325);
PAINT WHITE (-3325 4325);
FORCEPROP 2 LAST BOM_COST SM_CONTROLLER
J 0
(-3325 4425);
PAINT WHITE (-3325 4425);
DISPLAY INVISIBLE (-3325 4425);
FORCEPROP 2 LAST CDS_LIB mstr_symbols
J 0
(-3175 4475);
PAINT WHITE (-3175 4475);
DISPLAY INVISIBLE (-3175 4475);
FORCEPROP 1 LAST COMMENT_BODY TRUE
J 0
(-3150 4575);
DISPLAY 1.319149 (-3150 4575);
PAINT WHITE (-3150 4575);
DISPLAY INVISIBLE (-3150 4575);
FORCEPROP 2 LAST ROOM BMC
J 0
(-3325 4425);
PAINT WHITE (-3325 4425);
DISPLAY INVISIBLE (-3325 4425);
FORCEADD INTEL_CORP_BPAGE..1
(4250 200);
FORCEPROP 1 LAST CDS_CON_LAST_MODIFIED Tue Dec 01 11:51:50 2015
J 0
(2825 525);
PAINT ORANGE (2825 525);
DISPLAY INVISIBLE (2825 525);
FORCEPROP 1 LAST CUSTOM_TXT_CDS <CURRENT_DESIGN_SHEET> OF <TOTAL_DESIGN_SHEETS>
J 0
(3750 225);
PAINT GREEN (3750 225);
FORCEPROP 1 LAST CUSTOM_TXT_CDS <CON_LAST_MODIFIED>
J 0
(2325 550);
PAINT GREEN (2325 550);
FORCEPROP 2 LAST CUSTOM_TXT_CDS <XR_PAGE_TITLE>
J 0
(-3640 5450);
DISPLAY 0.638298 (-3640 5450);
PAINT PINK (-3640 5450);
DISPLAY INVISIBLE (-3640 5450);
FORCEPROP 1 LAST SCH_ADDRESS3 Santa Clara, CA 95052-8119
J 0
(275 225);
DISPLAY 0.617021 (275 225);
PAINT GREEN (275 225);
FORCEPROP 1 LAST SCH_ADDRESS2 P.O. BOX 58119
J 0
(275 275);
DISPLAY 0.617021 (275 275);
PAINT GREEN (275 275);
FORCEPROP 1 LAST SCH_ADDRESS1 2200 Mission College Blvd.
J 0
(275 325);
DISPLAY 0.617021 (275 325);
PAINT GREEN (275 325);
FORCEPROP 1 LAST SCH_TITLE CPU SIDE BAND:CPU1 DIMM CA VREF
J 0
(-3700 250);
DISPLAY 1.212766 (-3700 250);
PAINT ORANGE (-3700 250);
FORCEPROP 1 LAST SCH_NUMBER H4694802
J 0
(2950 350);
DISPLAY 1.212766 (2950 350);
PAINT YELLOW (2950 350);
FORCEPROP 1 LAST SCH_DEPT BESD
J 1
(-200 300);
DISPLAY 1.212766 (-200 300);
PAINT YELLOW (-200 300);
FORCEPROP 1 LAST SCH_REV 2.420
J 0
(4000 350);
DISPLAY 0.978723 (4000 350);
PAINT YELLOW (4000 350);
FORCEPROP 2 LAST PAGE_BORDER TRUE
J 0
(-3640 5450);
DISPLAY 0.638298 (-3640 5450);
PAINT PINK (-3640 5450);
DISPLAY INVISIBLE (-3640 5450);
FORCEPROP 2 LAST CDS_LIB mstr_symbols
J 0
(4250 200);
PAINT MONO (4250 200);
DISPLAY INVISIBLE (4250 200);
FORCEPROP 1 LAST COMMENT_BODY TRUE
J 0
(4262 212);
DISPLAY 0.468085 (4262 212);
PAINT GREEN (4262 212);
DISPLAY INVISIBLE (4262 212);
FORCEPROP 2 LAST CDS_XR_PAGE_TITLE CR-100 : @BASEBOARD_FAB2_LIB.BASEBOARD_FAB2(SCH_1):PAGE100
J 0
(-3640 5450);
DISPLAY 0.638298 (-3640 5450);
PAINT PINK (-3640 5450);
DISPLAY INVISIBLE (-3640 5450);
WIRE 16 -1 (-1900 2475)(-1900 2375);
WIRE 16 -1 (-1825 1425)(-1825 1525);
WIRE 16 -1 (-2125 1425)(-1825 1425);
WIRE 16 -1 (-2350 1425)(-2125 1425);
WIRE 16 -1 (-2125 1425)(-2125 1350);
WIRE 16 -1 (-2350 1550)(-2350 1425);
WIRE 16 -1 (450 4150)(450 4050);
WIRE 16 -1 (450 2475)(450 2375);
WIRE 16 -1 (525 3100)(525 3200);
WIRE 16 -1 (225 3100)(525 3100);
WIRE 16 -1 (225 3100)(0 3100);
WIRE 16 -1 (225 3100)(225 3025);
WIRE 16 -1 (0 3225)(0 3100);
WIRE 16 -1 (525 1425)(525 1525);
WIRE 16 -1 (225 1425)(525 1425);
WIRE 16 -1 (0 1425)(225 1425);
WIRE 16 -1 (225 1425)(225 1350);
WIRE 16 -1 (0 1550)(0 1425);
WIRE 16 -1 (2900 4150)(2900 4050);
WIRE 16 -1 (2900 2475)(2900 2375);
WIRE 16 -1 (2975 3100)(2975 3200);
WIRE 16 -1 (2675 3100)(2975 3100);
WIRE 16 -1 (2675 3100)(2450 3100);
WIRE 16 -1 (2675 3100)(2675 3025);
WIRE 16 -1 (2450 3225)(2450 3100);
WIRE 16 -1 (2975 1425)(2975 1525);
WIRE 16 -1 (2675 1425)(2975 1425);
WIRE 16 -1 (2450 1425)(2675 1425);
WIRE 16 -1 (2675 1425)(2675 1350);
WIRE 16 -1 (2450 1550)(2450 1425);
WIRE 16 -1 (-1900 4150)(-1900 4050);
WIRE 16 -1 (-1825 3100)(-1825 3200);
WIRE 16 -1 (-2125 3100)(-1825 3100);
WIRE 16 -1 (-2125 3100)(-2350 3100);
WIRE 16 -1 (-2125 3100)(-2125 3025);
WIRE 16 -1 (-2350 3225)(-2350 3100);
WIRE 16 -1 (-2350 1950)(-2225 1950);
WIRE 16 -1 (-2350 1750)(-2350 1950);
WIRE 16 -1 (-2350 1950)(-2800 1950);
FORCEPROP 2 LAST SIG_NAME M_K_CPU_VREF
J 0
(-2725 1960);
DISPLAY 0.617021 (-2725 1960);
PAINT ORANGE (-2725 1960);
WIRE 16 -1 (-2350 3625)(-2225 3625);
WIRE 16 -1 (-2350 3425)(-2350 3625);
WIRE 16 -1 (-2350 3625)(-2800 3625);
FORCEPROP 2 LAST SIG_NAME M_G_CPU_VREF
J 0
(-2725 3635);
DISPLAY 0.617021 (-2725 3635);
PAINT ORANGE (-2725 3635);
WIRE 16 -1 (-2025 1950)(-1900 1950);
WIRE 16 -1 (-1900 1950)(-1900 2175);
WIRE 16 -1 (-1825 1950)(-1900 1950);
FORCEPROP 2 LAST SIG_NAME M_K_VREF
J 0
(-1850 1960);
DISPLAY 0.617021 (-1850 1960);
PAINT ORANGE (-1850 1960);
WIRE 16 -1 (-1525 1950)(-1825 1950);
WIRE 16 -1 (-1825 1725)(-1825 1950);
WIRE 16 -1 (-1825 3400)(-1825 3625);
WIRE 16 -1 (-1525 3625)(-1825 3625);
WIRE 16 -1 (-1825 3625)(-1900 3625);
FORCEPROP 2 LAST SIG_NAME M_G_VREF
J 0
(-1850 3635);
DISPLAY 0.617021 (-1850 3635);
PAINT ORANGE (-1850 3635);
WIRE 16 -1 (-1900 3625)(-1900 3850);
WIRE 16 -1 (-2025 3625)(-1900 3625);
WIRE 16 -1 (0 3625)(125 3625);
WIRE 16 -1 (0 3625)(-450 3625);
FORCEPROP 2 LAST SIG_NAME M_H_CPU_VREF
J 0
(-375 3635);
DISPLAY 0.617021 (-375 3635);
PAINT ORANGE (-375 3635);
WIRE 16 -1 (0 3425)(0 3625);
WIRE 16 -1 (0 1950)(125 1950);
WIRE 16 -1 (0 1950)(-450 1950);
FORCEPROP 2 LAST SIG_NAME M_L_CPU_VREF
J 0
(-375 1960);
DISPLAY 0.617021 (-375 1960);
PAINT ORANGE (-375 1960);
WIRE 16 -1 (0 1750)(0 1950);
WIRE 16 -1 (325 1950)(450 1950);
WIRE 16 -1 (450 1950)(450 2175);
WIRE 16 -1 (525 1950)(450 1950);
FORCEPROP 2 LAST SIG_NAME M_L_VREF
J 0
(500 1960);
DISPLAY 0.617021 (500 1960);
PAINT ORANGE (500 1960);
WIRE 16 -1 (825 1950)(525 1950);
WIRE 16 -1 (525 1725)(525 1950);
WIRE 16 -1 (525 3400)(525 3625);
WIRE 16 -1 (825 3625)(525 3625);
WIRE 16 -1 (525 3625)(450 3625);
FORCEPROP 2 LAST SIG_NAME M_H_VREF
J 0
(500 3635);
DISPLAY 0.617021 (500 3635);
PAINT ORANGE (500 3635);
WIRE 16 -1 (450 3625)(450 3850);
WIRE 16 -1 (325 3625)(450 3625);
WIRE 16 -1 (2450 1950)(2575 1950);
WIRE 16 -1 (2450 1750)(2450 1950);
WIRE 16 -1 (2450 1950)(2000 1950);
FORCEPROP 2 LAST SIG_NAME M_M_CPU_VREF
J 0
(2075 1960);
DISPLAY 0.617021 (2075 1960);
PAINT ORANGE (2075 1960);
WIRE 16 -1 (2775 1950)(2900 1950);
WIRE 16 -1 (2900 1950)(2900 2175);
WIRE 16 -1 (2975 1950)(2900 1950);
FORCEPROP 2 LAST SIG_NAME M_M_VREF
J 0
(2950 1960);
DISPLAY 0.617021 (2950 1960);
PAINT ORANGE (2950 1960);
WIRE 16 -1 (3275 1950)(2975 1950);
WIRE 16 -1 (2975 1725)(2975 1950);
WIRE 16 -1 (2450 3625)(2575 3625);
WIRE 16 -1 (2450 3425)(2450 3625);
WIRE 16 -1 (2450 3625)(2000 3625);
FORCEPROP 2 LAST SIG_NAME M_J_CPU_VREF
J 0
(2075 3635);
DISPLAY 0.617021 (2075 3635);
PAINT ORANGE (2075 3635);
WIRE 16 -1 (2975 3400)(2975 3625);
WIRE 16 -1 (3275 3625)(2975 3625);
WIRE 16 -1 (2975 3625)(2900 3625);
FORCEPROP 2 LAST SIG_NAME M_J_VREF
J 0
(2950 3635);
DISPLAY 0.617021 (2950 3635);
PAINT ORANGE (2950 3635);
WIRE 16 -1 (2900 3625)(2900 3850);
WIRE 16 -1 (2775 3625)(2900 3625);
DOT 1 (0 3625);
DOT 1 (2675 1425);
DOT 1 (2450 1950);
DOT 1 (2675 3100);
DOT 1 (2450 3625);
DOT 1 (2975 1950);
DOT 1 (2900 1950);
DOT 1 (2900 3625);
DOT 1 (2975 3625);
DOT 1 (225 1425);
DOT 1 (0 1950);
DOT 1 (225 3100);
DOT 1 (525 1950);
DOT 1 (450 1950);
DOT 1 (450 3625);
DOT 1 (525 3625);
DOT 1 (-1825 3625);
DOT 1 (-1900 3625);
DOT 1 (-1900 1950);
DOT 1 (-1825 1950);
DOT 1 (-2350 3625);
DOT 1 (-2125 3100);
DOT 1 (-2350 1950);
DOT 1 (-2125 1425);
QUIT
